G04 ================== begin FILE IDENTIFICATION RECORD ==================*
G04 Layout Name:  12433-2a.brd*
G04 Film Name:    12433-2a_X_Y*
G04 File Format:  Gerber RS274X*
G04 File Origin:  Cadence Allegro 16.5-S056*
G04 Origin Date:  Fri Dec 11 16:58:35 2015*
G04 *
G04 Layer:  BOARD GEOMETRY/PANEL_DRAWING*
G04 *
G04 Offset:    (0.00 0.00)*
G04 Mirror:    No*
G04 Mode:      Positive*
G04 Rotation:  0*
G04 FullContactRelief:  No*
G04 UndefLineWidth:     6.00*
G04 ================== end FILE IDENTIFICATION RECORD ====================*
%FSLAX35Y35*MOIN*%
%IR0*IPPOS*OFA0.00000B0.00000*MIA0B0*SFA1.00000B1.00000*%
%ADD10C,.006*%
G75*
%LPD*%
G75*
G54D10*
G01X-552193Y-84022D02*
Y2112671D01*
G01X2572413Y-84022D02*
X-552193D01*
G01X-533256Y-65085D02*
Y2093734D01*
G01X2553476Y-65085D02*
X-533256D01*
G01X-545092Y39447D02*
X-544381Y38311D01*
X-543529Y37554D01*
X-542535Y37175D01*
X-541399Y37554D01*
X-540547Y38311D01*
X-539694Y39447D01*
X-539410Y40962D01*
Y48537D01*
G01X-552193Y150797D02*
X-533256D01*
G01X-543955Y264419D02*
X-540547D01*
G01X-542251D02*
Y253057D01*
G01X-543955D02*
X-540547D01*
G01X-552193Y366679D02*
X-533256D01*
G01X-552193D02*
X-533256D01*
G01X-545234Y468749D02*
Y480111D01*
G01X-539268D02*
Y468749D01*
G01Y474430D02*
X-545234D01*
G01X-552193Y582561D02*
X-533256D01*
G01X-552193D02*
X-533256D01*
G01X-541399Y690312D02*
X-538558D01*
Y686903D01*
X-539410Y685767D01*
X-540405Y685010D01*
X-541825Y684631D01*
X-543245Y685010D01*
X-544239Y685767D01*
X-545092Y686903D01*
X-545660Y688229D01*
X-545944Y689744D01*
Y691069D01*
X-545660Y692205D01*
X-545092Y693531D01*
X-544239Y694667D01*
X-543387Y695425D01*
X-542251Y695993D01*
X-541257D01*
X-540121Y695614D01*
X-539268Y694857D01*
G01X-552193Y798443D02*
X-533256D01*
G01X-552193D02*
X-533256D01*
G01X-545328Y900703D02*
Y912065D01*
X-539930D01*
G01X-541919Y906573D02*
X-545328D01*
G01X-552193Y1014325D02*
X-533256D01*
G01X-552193D02*
X-533256D01*
G01X-552193D02*
X-533256D01*
G01X-539410Y1116774D02*
X-545092D01*
Y1128136D01*
X-539410D01*
G01X-541683Y1122644D02*
X-545092D01*
G01X-552193Y1230206D02*
X-533256D01*
G01X-552193D02*
X-533256D01*
G01X-545376Y1332466D02*
Y1343828D01*
X-542535D01*
X-541399Y1343260D01*
X-540547Y1342502D01*
X-539836Y1341366D01*
X-539268Y1340040D01*
X-539126Y1338147D01*
X-539268Y1336253D01*
X-539836Y1334928D01*
X-540547Y1333791D01*
X-541399Y1333034D01*
X-542535Y1332466D01*
X-545376D01*
G01X-552193Y1446088D02*
X-533256D01*
G01X-552193D02*
X-533256D01*
G01X-539126Y1558953D02*
X-539979Y1559521D01*
X-540973Y1559900D01*
X-542109D01*
X-543387Y1559332D01*
X-544381Y1558385D01*
X-545092Y1557249D01*
X-545660Y1555355D01*
X-545802Y1553651D01*
X-545518Y1551947D01*
X-545092Y1550810D01*
X-544239Y1549674D01*
X-543245Y1548917D01*
X-542251Y1548538D01*
X-541257D01*
X-540263Y1548917D01*
X-539410Y1549485D01*
X-538700Y1550242D01*
G01X-552193Y1661970D02*
X-533256D01*
G01X-552193D02*
X-533256D01*
G01X-541115Y1770290D02*
X-540547Y1770858D01*
X-540121Y1771804D01*
X-539836Y1773130D01*
X-540121Y1774266D01*
X-540689Y1775024D01*
X-541683Y1775592D01*
X-545518D01*
Y1764230D01*
X-540831D01*
X-539836Y1764987D01*
X-539268Y1766124D01*
X-538984Y1767449D01*
X-539268Y1768775D01*
X-540121Y1769911D01*
X-541115Y1770290D01*
X-545518D01*
G01X-552193Y1877852D02*
X-533256D01*
G01X-545802Y1980112D02*
X-542251Y1991474D01*
X-538700Y1980112D01*
G01X-539979Y1984089D02*
X-544524D01*
G01X-552193Y2112671D02*
X2572413D01*
G01X-533256Y2093734D02*
X2553476D01*
G01X-415373Y-80235D02*
Y-68873D01*
X-417077Y-71145D01*
G01Y-80235D02*
X-413669D01*
G01X-415373Y2097521D02*
Y2108883D01*
X-417077Y2106611D01*
G01Y2097521D02*
X-413669D01*
G01X-335560Y1966875D02*
X-334992Y1966244D01*
X-334329Y1965865D01*
X-333477Y1965739D01*
X-332624Y1965991D01*
X-331962Y1966496D01*
X-331488Y1967380D01*
X-331393Y1968390D01*
X-331583Y1969400D01*
X-332056Y1970032D01*
X-332719Y1970536D01*
X-333382Y1970663D01*
X-334045Y1970536D01*
X-334897Y1970032D01*
X-334613Y1973314D01*
X-332056D01*
G01X-325902D02*
X-326659Y1973062D01*
X-327227Y1972430D01*
X-327606Y1971673D01*
X-327890Y1970663D01*
X-327985Y1969526D01*
X-327890Y1968390D01*
X-327606Y1967380D01*
X-327227Y1966623D01*
X-326659Y1965991D01*
X-325902Y1965739D01*
X-325144Y1965991D01*
X-324576Y1966623D01*
X-324197Y1967380D01*
X-323913Y1968390D01*
X-323818Y1969526D01*
X-323913Y1970663D01*
X-324197Y1971673D01*
X-324576Y1972430D01*
X-325144Y1973062D01*
X-325902Y1973314D01*
G01X-318327D02*
X-319084Y1973062D01*
X-319652Y1972430D01*
X-320031Y1971673D01*
X-320315Y1970663D01*
X-320410Y1969526D01*
X-320315Y1968390D01*
X-320031Y1967380D01*
X-319652Y1966623D01*
X-319084Y1965991D01*
X-318327Y1965739D01*
X-317569Y1965991D01*
X-317001Y1966623D01*
X-316622Y1967380D01*
X-316338Y1968390D01*
X-316243Y1969526D01*
X-316338Y1970663D01*
X-316622Y1971673D01*
X-317001Y1972430D01*
X-317569Y1973062D01*
X-318327Y1973314D01*
G01X-310752Y1965487D02*
X-310941Y1965613D01*
Y1965865D01*
X-310752Y1965991D01*
X-310562Y1965865D01*
Y1965613D01*
X-310752Y1965487D01*
G01X-303177Y1973314D02*
X-303934Y1973062D01*
X-304502Y1972430D01*
X-304881Y1971673D01*
X-305165Y1970663D01*
X-305260Y1969526D01*
X-305165Y1968390D01*
X-304881Y1967380D01*
X-304502Y1966623D01*
X-303934Y1965991D01*
X-303177Y1965739D01*
X-302419Y1965991D01*
X-301851Y1966623D01*
X-301472Y1967380D01*
X-301188Y1968390D01*
X-301093Y1969526D01*
X-301188Y1970663D01*
X-301472Y1971673D01*
X-301851Y1972430D01*
X-302419Y1973062D01*
X-303177Y1973314D01*
G01X-295602D02*
X-296359Y1973062D01*
X-296927Y1972430D01*
X-297306Y1971673D01*
X-297590Y1970663D01*
X-297685Y1969526D01*
X-297590Y1968390D01*
X-297306Y1967380D01*
X-296927Y1966623D01*
X-296359Y1965991D01*
X-295602Y1965739D01*
X-294844Y1965991D01*
X-294276Y1966623D01*
X-293897Y1967380D01*
X-293613Y1968390D01*
X-293518Y1969526D01*
X-293613Y1970663D01*
X-293897Y1971673D01*
X-294276Y1972430D01*
X-294844Y1973062D01*
X-295602Y1973314D01*
G01X-307905Y-65085D02*
Y-84022D01*
G01X-319994Y-24242D02*
Y-17943D01*
X-322907Y-22457D01*
X-318971D01*
G01X-315664Y-22142D02*
X-313616D01*
G01X-309680Y-24242D02*
Y-20043D01*
G01Y-21093D02*
X-309365Y-20568D01*
X-308892Y-20148D01*
X-308262Y-20043D01*
X-307711Y-20148D01*
X-307239Y-20568D01*
X-307002Y-21303D01*
Y-24242D01*
G01X-303774Y-22982D02*
X-303302Y-23717D01*
X-302672Y-24137D01*
X-301963Y-24242D01*
X-301333Y-24137D01*
X-300703Y-23612D01*
X-300310Y-22982D01*
X-300231Y-22352D01*
X-300389Y-21618D01*
X-300940Y-21093D01*
X-301491Y-20882D01*
X-302200D01*
G01X-301491D02*
X-301018Y-20568D01*
X-300625Y-20043D01*
X-300467Y-19413D01*
X-300625Y-18783D01*
X-301018Y-18258D01*
X-301727Y-17943D01*
X-302436Y-18048D01*
X-303144Y-18468D01*
G01X-295743Y-24452D02*
X-295901Y-24347D01*
Y-24137D01*
X-295743Y-24032D01*
X-295585Y-24137D01*
Y-24347D01*
X-295743Y-24452D01*
G01X-291176Y-23297D02*
X-290704Y-23822D01*
X-290153Y-24137D01*
X-289444Y-24242D01*
X-288735Y-24032D01*
X-288184Y-23612D01*
X-287791Y-22877D01*
X-287712Y-22037D01*
X-287869Y-21198D01*
X-288263Y-20673D01*
X-288814Y-20253D01*
X-289365Y-20148D01*
X-289916Y-20253D01*
X-290625Y-20673D01*
X-290389Y-17943D01*
X-288263D01*
G01X-284877Y-23297D02*
X-284405Y-23822D01*
X-283854Y-24137D01*
X-283145Y-24242D01*
X-282436Y-24032D01*
X-281885Y-23612D01*
X-281492Y-22877D01*
X-281413Y-22037D01*
X-281570Y-21198D01*
X-281964Y-20673D01*
X-282515Y-20253D01*
X-283066Y-20148D01*
X-283617Y-20253D01*
X-284326Y-20673D01*
X-284090Y-17943D01*
X-281964D01*
G01X-321593Y-35221D02*
Y-31022D01*
G01Y-32072D02*
X-321278Y-31547D01*
X-320805Y-31127D01*
X-320175Y-31022D01*
X-319624Y-31127D01*
X-319152Y-31547D01*
X-318915Y-32282D01*
Y-35221D01*
G01X-315923D02*
X-313955Y-28922D01*
X-311987Y-35221D01*
G01X-312695Y-33016D02*
X-315215D01*
G01X-308522Y-33121D02*
X-306632D01*
G01X-307656Y-31757D02*
Y-34486D01*
G01X-301357Y-28922D02*
X-301987Y-29132D01*
X-302459Y-29657D01*
X-302774Y-30287D01*
X-303010Y-31127D01*
X-303089Y-32072D01*
X-303010Y-33016D01*
X-302774Y-33856D01*
X-302459Y-34486D01*
X-301987Y-35011D01*
X-301357Y-35221D01*
X-300727Y-35011D01*
X-300255Y-34486D01*
X-299940Y-33856D01*
X-299704Y-33016D01*
X-299625Y-32072D01*
X-299704Y-31127D01*
X-299940Y-30287D01*
X-300255Y-29657D01*
X-300727Y-29132D01*
X-301357Y-28922D01*
G01X-295058Y-35431D02*
X-295216Y-35326D01*
Y-35116D01*
X-295058Y-35011D01*
X-294900Y-35116D01*
Y-35326D01*
X-295058Y-35431D01*
G01X-288759Y-28922D02*
X-289389Y-29132D01*
X-289861Y-29657D01*
X-290176Y-30287D01*
X-290412Y-31127D01*
X-290491Y-32072D01*
X-290412Y-33016D01*
X-290176Y-33856D01*
X-289861Y-34486D01*
X-289389Y-35011D01*
X-288759Y-35221D01*
X-288129Y-35011D01*
X-287657Y-34486D01*
X-287342Y-33856D01*
X-287106Y-33016D01*
X-287027Y-32072D01*
X-287106Y-31127D01*
X-287342Y-30287D01*
X-287657Y-29657D01*
X-288129Y-29132D01*
X-288759Y-28922D01*
G01X-282618Y-35221D02*
X-282460Y-33856D01*
X-282224Y-32702D01*
X-281909Y-31652D01*
X-281515Y-30497D01*
X-280885Y-28922D01*
X-284035D01*
G01X-277893Y-34276D02*
X-277421Y-34801D01*
X-276870Y-35116D01*
X-276161Y-35221D01*
X-275452Y-35011D01*
X-274901Y-34591D01*
X-274508Y-33856D01*
X-274429Y-33016D01*
X-274586Y-32177D01*
X-274980Y-31652D01*
X-275531Y-31232D01*
X-276082Y-31127D01*
X-276633Y-31232D01*
X-277342Y-31652D01*
X-277106Y-28922D01*
X-274980D01*
G01X-301178Y-44501D02*
X-299130D01*
G01X-293855Y-40302D02*
X-294485Y-40512D01*
X-294957Y-41037D01*
X-295272Y-41667D01*
X-295508Y-42507D01*
X-295587Y-43452D01*
X-295508Y-44396D01*
X-295272Y-45236D01*
X-294957Y-45866D01*
X-294485Y-46391D01*
X-293855Y-46601D01*
X-293225Y-46391D01*
X-292753Y-45866D01*
X-292438Y-45236D01*
X-292202Y-44396D01*
X-292123Y-43452D01*
X-292202Y-42507D01*
X-292438Y-41667D01*
X-292753Y-41037D01*
X-293225Y-40512D01*
X-293855Y-40302D01*
G01X-283304Y-46601D02*
Y-40302D01*
X-281257Y-45551D01*
X-279210Y-40302D01*
Y-46601D01*
G01X-277005D02*
Y-40302D01*
X-274958Y-45551D01*
X-272911Y-40302D01*
Y-46601D01*
G01X-261811Y-19685D02*
X-281496D01*
G01X-317941Y3624D02*
X-318698Y3372D01*
X-319266Y2740D01*
X-319645Y1983D01*
X-319929Y973D01*
X-320024Y-164D01*
X-319929Y-1300D01*
X-319645Y-2310D01*
X-319266Y-3067D01*
X-318698Y-3699D01*
X-317941Y-3951D01*
X-317183Y-3699D01*
X-316615Y-3067D01*
X-316236Y-2310D01*
X-315952Y-1300D01*
X-315857Y-164D01*
X-315952Y973D01*
X-316236Y1983D01*
X-316615Y2740D01*
X-317183Y3372D01*
X-317941Y3624D01*
G01X-310366Y-4203D02*
X-310555Y-4077D01*
Y-3825D01*
X-310366Y-3699D01*
X-310176Y-3825D01*
Y-4077D01*
X-310366Y-4203D01*
G01X-302791Y3624D02*
X-303548Y3372D01*
X-304116Y2740D01*
X-304495Y1983D01*
X-304779Y973D01*
X-304874Y-164D01*
X-304779Y-1300D01*
X-304495Y-2310D01*
X-304116Y-3067D01*
X-303548Y-3699D01*
X-302791Y-3951D01*
X-302033Y-3699D01*
X-301465Y-3067D01*
X-301086Y-2310D01*
X-300802Y-1300D01*
X-300707Y-164D01*
X-300802Y973D01*
X-301086Y1983D01*
X-301465Y2740D01*
X-302033Y3372D01*
X-302791Y3624D01*
G01X-295216D02*
X-295973Y3372D01*
X-296541Y2740D01*
X-296920Y1983D01*
X-297204Y973D01*
X-297299Y-164D01*
X-297204Y-1300D01*
X-296920Y-2310D01*
X-296541Y-3067D01*
X-295973Y-3699D01*
X-295216Y-3951D01*
X-294458Y-3699D01*
X-293890Y-3067D01*
X-293511Y-2310D01*
X-293227Y-1300D01*
X-293132Y-164D01*
X-293227Y973D01*
X-293511Y1983D01*
X-293890Y2740D01*
X-294458Y3372D01*
X-295216Y3624D01*
G01X-284993Y-14D02*
X-300741D01*
G01X-269245Y0D02*
X-284993Y-14D01*
G01X-286094Y1969676D02*
X-301842D01*
G01X-270346Y1968504D02*
X-286094Y1969676D01*
G01X-307905Y2112671D02*
Y2093734D01*
G01X-222441Y19685D02*
X-261811Y-19685D01*
G01X-222441Y169326D02*
Y39370D01*
G01X-174370Y0D02*
X-269245D01*
G01X-215453Y19685D02*
G03I-6988J0D01*
G01D02*
G03I-6988J0D01*
G01D02*
G03I-6988J0D01*
G01X-222441Y39370D02*
G03X-214567Y31496I7874J0D01*
G01X-242126Y15000D02*
G03X-227126Y0I15000J0D01*
G01X-242126Y1953504D02*
Y15000D01*
G01X-84646Y0D02*
X-227126D01*
G01X-228941Y8085D02*
X-234041Y13185D01*
G01X-222441Y19685D02*
X-228941Y8085D01*
G01X-234041Y13185D02*
X-222441Y19685D01*
G01X-214567Y169326D02*
G03X-222441I-3937J0D01*
G01X-214567D02*
G03X-222441I-3937J0D01*
G01Y436255D02*
Y200034D01*
G01D02*
G03X-214567I3937J0D01*
G01X-222441D02*
G03X-214567I3937J0D01*
G01Y436255D02*
G03X-222441I-3937J0D01*
G01X-214567D02*
G03X-222441I-3937J0D01*
G01Y703184D02*
Y466963D01*
G01D02*
G03X-214567I3937J0D01*
G01X-222441D02*
G03X-214567I3937J0D01*
G01Y703184D02*
G03X-222441I-3937J0D01*
G01X-214567D02*
G03X-222441I-3937J0D01*
G01Y970901D02*
Y733892D01*
G01D02*
G03X-214567I3937J0D01*
G01X-222441D02*
G03X-214567I3937J0D01*
G01X-222441Y1234681D02*
Y997672D01*
G01X-214567Y970901D02*
G03X-222441I-3937J0D01*
G01Y997672D02*
G03X-214567I3937J0D01*
G01Y970901D02*
G03X-222441I-3937J0D01*
G01Y997672D02*
G03X-214567I3937J0D01*
G01X-222441Y1501610D02*
Y1265389D01*
G01D02*
G03X-214567I3937J0D01*
G01Y1234681D02*
G03X-222441I-3937J0D01*
G01Y1265389D02*
G03X-214567I3937J0D01*
G01Y1234681D02*
G03X-222441I-3937J0D01*
G01X-214567Y1501610D02*
G03X-222441I-3937J0D01*
G01X-214567D02*
G03X-222441I-3937J0D01*
G01Y1768539D02*
Y1532318D01*
G01D02*
G03X-214567I3937J0D01*
G01X-222441D02*
G03X-214567I3937J0D01*
G01Y1768539D02*
G03X-222441I-3937J0D01*
G01X-214567D02*
G03X-222441I-3937J0D01*
G01Y1799247D02*
G03X-214567I3937J0D01*
G01X-222441D02*
G03X-214567I3937J0D01*
G01X-222441Y1929134D02*
Y1799247D01*
G01X-214567Y1937008D02*
G03X-222441Y1929134I0J-7874D01*
G01X-186098Y1968504D02*
X-270346D01*
G01X-242126Y1953750D02*
Y2008799D01*
G01X-215453Y1948819D02*
G03I-6988J0D01*
G01D02*
G03I-6988J0D01*
G01D02*
G03I-6988J0D01*
G01X-227126Y1968504D02*
G03X-242126Y1953504I0J-15000D01*
G01X-84638Y1968504D02*
X-227126D01*
G01X-245764Y2011993D02*
X-245512Y2011236D01*
X-244880Y2010668D01*
X-244123Y2010289D01*
X-243113Y2010005D01*
X-241976Y2009910D01*
X-240840Y2010005D01*
X-239830Y2010289D01*
X-239073Y2010668D01*
X-238441Y2011236D01*
X-238189Y2011993D01*
X-238441Y2012751D01*
X-239073Y2013319D01*
X-239830Y2013698D01*
X-240840Y2013982D01*
X-241976Y2014077D01*
X-243113Y2013982D01*
X-244123Y2013698D01*
X-244880Y2013319D01*
X-245512Y2012751D01*
X-245764Y2011993D01*
G01X-237937Y2019568D02*
X-238063Y2019379D01*
X-238315D01*
X-238441Y2019568D01*
X-238315Y2019758D01*
X-238063D01*
X-237937Y2019568D01*
G01X-245764Y2027143D02*
X-245512Y2026386D01*
X-244880Y2025818D01*
X-244123Y2025439D01*
X-243113Y2025155D01*
X-241976Y2025060D01*
X-240840Y2025155D01*
X-239830Y2025439D01*
X-239073Y2025818D01*
X-238441Y2026386D01*
X-238189Y2027143D01*
X-238441Y2027901D01*
X-239073Y2028469D01*
X-239830Y2028848D01*
X-240840Y2029132D01*
X-241976Y2029227D01*
X-243113Y2029132D01*
X-244123Y2028848D01*
X-244880Y2028469D01*
X-245512Y2027901D01*
X-245764Y2027143D01*
G01Y2034718D02*
X-245512Y2033961D01*
X-244880Y2033393D01*
X-244123Y2033014D01*
X-243113Y2032730D01*
X-241976Y2032635D01*
X-240840Y2032730D01*
X-239830Y2033014D01*
X-239073Y2033393D01*
X-238441Y2033961D01*
X-238189Y2034718D01*
X-238441Y2035476D01*
X-239073Y2036044D01*
X-239830Y2036423D01*
X-240840Y2036707D01*
X-241976Y2036802D01*
X-243113Y2036707D01*
X-244123Y2036423D01*
X-244880Y2036044D01*
X-245512Y2035476D01*
X-245764Y2034718D01*
G01X-200296Y-70767D02*
X-199443Y-69631D01*
X-198449Y-69062D01*
X-197313Y-68873D01*
X-195893Y-69252D01*
X-194898Y-70199D01*
X-194614Y-71335D01*
X-194756Y-72471D01*
X-195325Y-73418D01*
X-198165Y-75311D01*
X-199443Y-76637D01*
X-200296Y-78531D01*
X-200580Y-80235D01*
X-194614D01*
G01X-206693Y31496D02*
X-214567D01*
G01X-206693D02*
X-214567D01*
G01X-84646Y0D02*
X-199567D01*
G01X-214567Y43307D02*
G03X-210630Y39370I3937J0D01*
G01X-214567Y43307D02*
G03X-210630Y39370I3937J0D01*
G01X-80709D02*
X-210630D01*
G01X-80709D02*
X-210630D01*
G01X-175984Y31496D02*
X-84646D01*
G01X-206693D02*
G03Y39370I0J3937D01*
G01X-175984D02*
G03Y31496I0J-3937D01*
G01D02*
X-84646D01*
G01X-206693D02*
G03Y39370I0J3937D01*
G01X-175984D02*
G03Y31496I0J-3937D01*
G01X-189139Y28007D02*
X-173139D01*
G01Y12007D02*
Y28007D01*
G01X-189139Y12007D02*
X-173139D01*
G01X-189139Y28007D02*
Y12007D01*
G01X-183639Y17507D02*
X-178639D01*
G01Y22507D02*
X-183639D01*
G01Y17507D02*
Y22507D01*
G01X-178639D02*
Y17507D01*
G01X-181139D02*
Y22507D01*
G01X-183639Y20007D02*
X-178639D01*
G01X-214567Y43307D02*
Y1925197D01*
G01Y43307D02*
Y1925197D01*
G01Y149606D02*
Y43307D01*
G01Y149606D02*
Y43272D01*
G01Y1807087D02*
Y161417D01*
G01Y1807087D02*
Y161417D01*
G01Y1818898D02*
Y1925231D01*
G01Y1818898D02*
Y1925231D01*
G01Y1915382D02*
Y1977555D01*
G01X-210630Y1929134D02*
G03X-214567Y1925197I0J-3937D01*
G01X-210630Y1929134D02*
G03X-214567Y1925197I0J-3937D01*
G01X-210630Y1929134D02*
X-80709D01*
G01X-210630D02*
X-80709D01*
G01X-175984Y1937008D02*
G03Y1929134I0J-3937D01*
G01X-206693D02*
G03Y1937008I0J3937D01*
G01X-175984D02*
G03Y1929134I0J-3937D01*
G01X-206693D02*
G03Y1937008I0J3937D01*
G01X-214567Y1977555D02*
X-212116Y1993304D01*
G01X-214567Y1937008D02*
X-206693D01*
G01X-214567D02*
X-206693D01*
G01X-172445Y1939256D02*
X-188445D01*
G01Y1955256D02*
Y1939256D01*
G01X-172445Y1955256D02*
X-188445D01*
G01X-172445Y1939256D02*
Y1955256D01*
G01X-177945Y1949756D02*
X-182945D01*
G01Y1944756D02*
X-177945D01*
G01Y1949756D02*
Y1944756D01*
G01X-182945D02*
Y1949756D01*
G01X-180445D02*
Y1944756D01*
G01X-177945Y1947256D02*
X-182945D01*
G01X-175984Y1937008D02*
X-84638D01*
G01X-175984D02*
X-84638D01*
G01X-208179Y2012057D02*
X-209820Y2012246D01*
X-211209Y2012531D01*
X-212472Y2012909D01*
X-213860Y2013383D01*
X-215754Y2014140D01*
Y2010353D01*
G01X-207927Y2019821D02*
X-208053Y2019632D01*
X-208305D01*
X-208431Y2019821D01*
X-208305Y2020011D01*
X-208053D01*
X-207927Y2019821D01*
G01X-215754Y2027396D02*
X-215502Y2026639D01*
X-214870Y2026071D01*
X-214113Y2025692D01*
X-213103Y2025408D01*
X-211966Y2025313D01*
X-210830Y2025408D01*
X-209820Y2025692D01*
X-209063Y2026071D01*
X-208431Y2026639D01*
X-208179Y2027396D01*
X-208431Y2028154D01*
X-209063Y2028722D01*
X-209820Y2029101D01*
X-210830Y2029385D01*
X-211966Y2029480D01*
X-213103Y2029385D01*
X-214113Y2029101D01*
X-214870Y2028722D01*
X-215502Y2028154D01*
X-215754Y2027396D01*
G01Y2034971D02*
X-215502Y2034214D01*
X-214870Y2033646D01*
X-214113Y2033267D01*
X-213103Y2032983D01*
X-211966Y2032888D01*
X-210830Y2032983D01*
X-209820Y2033267D01*
X-209063Y2033646D01*
X-208431Y2034214D01*
X-208179Y2034971D01*
X-208431Y2035729D01*
X-209063Y2036297D01*
X-209820Y2036676D01*
X-210830Y2036960D01*
X-211966Y2037055D01*
X-213103Y2036960D01*
X-214113Y2036676D01*
X-214870Y2036297D01*
X-215502Y2035729D01*
X-215754Y2034971D01*
G01X-212116Y1993304D02*
Y2009052D01*
G01X-200296Y2106989D02*
X-199443Y2108125D01*
X-198449Y2108694D01*
X-197313Y2108883D01*
X-195893Y2108504D01*
X-194898Y2107557D01*
X-194614Y2106421D01*
X-194756Y2105285D01*
X-195325Y2104338D01*
X-198165Y2102445D01*
X-199443Y2101119D01*
X-200296Y2099225D01*
X-200580Y2097521D01*
X-194614D01*
G01X-140832Y934748D02*
Y984748D01*
G01X-126458Y934748D02*
X-155208D01*
G01X-88236Y-65085D02*
Y-84022D01*
G01X-76772Y3937D02*
G03X-72835Y0I3937J0D01*
G01X-76772Y35433D02*
G03X-80709Y39370I-3937J0D01*
G01X-76772Y35433D02*
G03X-80709Y39370I-3937J0D01*
G01X-76772Y3937D02*
G03X-72835Y0I3937J0D01*
G01X-11811D02*
X-72835D01*
G01X-11811D02*
X-72835D01*
G01X-76772Y3937D02*
Y35433D01*
G01Y3937D02*
Y35433D01*
G01X-72835Y0D02*
X-11811D01*
G01X-76772Y3937D02*
G03X-72835Y0I3937J0D01*
G01X-84646Y7874D02*
Y0D01*
G01X-76772Y7874D02*
G03X-84646I-3937J0D01*
G01Y31496D02*
G03X-76772I3937J0D01*
G01X-72835Y0D02*
X-11811D01*
G01X-76772Y3937D02*
G03X-72835Y0I3937J0D01*
G01X-84646Y7874D02*
Y0D01*
G01X-76772Y7874D02*
G03X-84646I-3937J0D01*
G01Y31496D02*
G03X-76772I3937J0D01*
G01X-80709Y1929134D02*
G03X-76772Y1933071I0J3937D01*
G01X-80709Y1929134D02*
G03X-76772Y1933071I0J3937D01*
G01D02*
Y1964567D01*
G01Y1933071D02*
Y1964567D01*
G01X-76763Y1937008D02*
G03X-84638I-3937J0D01*
G01X-72835Y1968504D02*
G03X-76772Y1964567I0J-3937D01*
G01X-72835Y1968504D02*
G03X-76772Y1964567I0J-3937D01*
G01X-72835Y1968504D02*
X-11811D01*
G01X-72835D02*
X-11811D01*
G01X-72835D02*
G03X-76772Y1964567I0J-3937D01*
G01X-11811Y1968504D02*
X-72835D01*
G01X-84638Y1960889D02*
Y1968504D01*
G01Y1960889D02*
G03X-76763I3938J0D01*
G01X-72835Y1968504D02*
G03X-76772Y1964567I0J-3937D01*
G01X-11811Y1968504D02*
X-72835D01*
G01X-84638Y1960889D02*
Y1968504D01*
G01Y1960889D02*
G03X-76763I3938J0D01*
G01X-88236Y2112671D02*
Y2093734D01*
G01X-23622Y48780D02*
X-22441Y49370D01*
G01X-23622Y58780D02*
X-22441Y59370D01*
G01X-23622Y68780D02*
X-22441Y69370D01*
G01X-23622Y78780D02*
X-22441Y79370D01*
G01X-23622Y88780D02*
X-22441Y89370D01*
G01Y86850D02*
Y89370D01*
G01Y76850D02*
Y79370D01*
G01Y66850D02*
Y69370D01*
G01Y56850D02*
Y59370D01*
G01Y46850D02*
Y49370D01*
G01X-23622Y87441D02*
Y88780D01*
G01Y77441D02*
Y78780D01*
G01Y67441D02*
Y68780D01*
G01Y57441D02*
Y58780D01*
G01Y47441D02*
Y48780D01*
G01Y87441D02*
X-22441Y86850D01*
G01X-23622Y77441D02*
X-22441Y76850D01*
G01X-23622Y67441D02*
X-22441Y66850D01*
G01X-23622Y57441D02*
X-22441Y56850D01*
G01X-23622Y47441D02*
X-22441Y46850D01*
G01X0Y89370D02*
X-22441D01*
G01X0Y86850D02*
X-22441D01*
G01X0Y79370D02*
X-22441D01*
G01X0Y76850D02*
X-22441D01*
G01X0Y69370D02*
X-22441D01*
G01X0Y66850D02*
X-22441D01*
G01X0Y59370D02*
X-22441D01*
G01X0Y56850D02*
X-22441D01*
G01X0Y49370D02*
X-22441D01*
G01X0Y46850D02*
X-22441D01*
G01X-23622Y482008D02*
X-22441Y482598D01*
G01X-23622Y492008D02*
X-22441Y492598D01*
G01Y500079D02*
Y502598D01*
G01Y490079D02*
Y492598D01*
G01Y480079D02*
Y482598D01*
G01X-23622Y500669D02*
Y502008D01*
G01Y490669D02*
Y492008D01*
G01Y480669D02*
Y482008D01*
G01Y500669D02*
X-22441Y500079D01*
G01X-23622Y490669D02*
X-22441Y490079D01*
G01X-23622Y480669D02*
X-22441Y480079D01*
G01X0Y500079D02*
X-22441D01*
G01X0Y492598D02*
X-22441D01*
G01X0Y490079D02*
X-22441D01*
G01X0Y482598D02*
X-22441D01*
G01X0Y480079D02*
X-22441D01*
G01X-23622Y502008D02*
X-22441Y502598D01*
G01X-23622Y512008D02*
X-22441Y512598D01*
G01X-23622Y522008D02*
X-22441Y522598D01*
G01Y520079D02*
Y522598D01*
G01Y510079D02*
Y512598D01*
G01X-23622Y520669D02*
Y522008D01*
G01Y510669D02*
Y512008D01*
G01Y520669D02*
X-22441Y520079D01*
G01X-23622Y510669D02*
X-22441Y510079D01*
G01X0Y522598D02*
X-22441D01*
G01X0Y520079D02*
X-22441D01*
G01X0Y512598D02*
X-22441D01*
G01X0Y510079D02*
X-22441D01*
G01X0Y502598D02*
X-22441D01*
G01X-23622Y741850D02*
X-22441Y742441D01*
G01X-23622Y751850D02*
X-22441Y752441D01*
G01Y749921D02*
Y752441D01*
G01Y739921D02*
Y742441D01*
G01X-23622Y750512D02*
Y751850D01*
G01Y740512D02*
Y741850D01*
G01X0Y752441D02*
X-22441D01*
G01X0Y749921D02*
X-22441D01*
G01X0Y742441D02*
X-22441D01*
G01X0Y739921D02*
X-22441D01*
G01X-23622Y750512D02*
X-22441Y749921D01*
G01X-23622Y740512D02*
X-22441Y739921D01*
G01X-23622Y761850D02*
X-22441Y762441D01*
G01X-23622Y771850D02*
X-22441Y772441D01*
G01X-23622Y781850D02*
X-22441Y782441D01*
G01Y779921D02*
Y782441D01*
G01Y769921D02*
Y772441D01*
G01Y759921D02*
Y762441D01*
G01X-23622Y780512D02*
Y781850D01*
G01Y770512D02*
Y771850D01*
G01Y760512D02*
Y761850D01*
G01Y780512D02*
X-22441Y779921D01*
G01X-23622Y770512D02*
X-22441Y769921D01*
G01X-23622Y760512D02*
X-22441Y759921D01*
G01X0Y782441D02*
X-22441D01*
G01X0Y779921D02*
X-22441D01*
G01X0Y772441D02*
X-22441D01*
G01X0Y769921D02*
X-22441D01*
G01X0Y762441D02*
X-22441D01*
G01X0Y759921D02*
X-22441D01*
G01X0Y1216063D02*
X-22441D01*
G01X0Y1208583D02*
X-22441D01*
G01X0Y1206063D02*
X-22441D01*
G01X0Y1198583D02*
X-22441D01*
G01X0Y1196063D02*
X-22441D01*
G01X-23622Y1216654D02*
X-22441Y1216063D01*
G01X-23622Y1206654D02*
X-22441Y1206063D01*
G01X0Y1188583D02*
X-22441D01*
G01X0Y1186063D02*
X-22441D01*
G01X-23622Y1196654D02*
X-22441Y1196063D01*
G01X-23622Y1186654D02*
X-22441Y1186063D01*
G01Y1216063D02*
Y1218583D01*
G01Y1206063D02*
Y1208583D01*
G01Y1196063D02*
Y1198583D01*
G01Y1186063D02*
Y1188583D01*
G01X-23622Y1216654D02*
Y1217992D01*
G01Y1206654D02*
Y1207992D01*
G01Y1196654D02*
Y1197992D01*
G01Y1186654D02*
Y1187992D01*
G01D02*
X-22441Y1188583D01*
G01X-23622Y1197992D02*
X-22441Y1198583D01*
G01X-23622Y1207992D02*
X-22441Y1208583D01*
G01X0Y1228583D02*
X-22441D01*
G01X0Y1226063D02*
X-22441D01*
G01X0Y1218583D02*
X-22441D01*
G01X-23622Y1226654D02*
X-22441Y1226063D01*
G01D02*
Y1228583D01*
G01X-23622Y1226654D02*
Y1227992D01*
G01Y1217992D02*
X-22441Y1218583D01*
G01X-23622Y1227992D02*
X-22441Y1228583D01*
G01X0Y1468425D02*
X-22441D01*
G01X0Y1465906D02*
X-22441D01*
G01X0Y1458425D02*
X-22441D01*
G01X0Y1455906D02*
X-22441D01*
G01X0Y1448425D02*
X-22441D01*
G01X0Y1445906D02*
X-22441D01*
G01X-23622Y1466496D02*
X-22441Y1465906D01*
G01X-23622Y1456496D02*
X-22441Y1455906D01*
G01X-23622Y1446496D02*
X-22441Y1445906D01*
G01Y1465906D02*
Y1468425D01*
G01Y1455906D02*
Y1458425D01*
G01Y1445906D02*
Y1448425D01*
G01X-23622Y1466496D02*
Y1467835D01*
G01Y1456496D02*
Y1457835D01*
G01Y1446496D02*
Y1447835D01*
G01D02*
X-22441Y1448425D01*
G01X-23622Y1457835D02*
X-22441Y1458425D01*
G01X-23622Y1467835D02*
X-22441Y1468425D01*
G01X0Y1488425D02*
X-22441D01*
G01X0Y1485906D02*
X-22441D01*
G01X0Y1478425D02*
X-22441D01*
G01X0Y1475906D02*
X-22441D01*
G01X-23622Y1486496D02*
X-22441Y1485906D01*
G01X-23622Y1476496D02*
X-22441Y1475906D01*
G01Y1485906D02*
Y1488425D01*
G01Y1475906D02*
Y1478425D01*
G01X-23622Y1486496D02*
Y1487835D01*
G01Y1476496D02*
Y1477835D01*
G01D02*
X-22441Y1478425D01*
G01X-23622Y1487835D02*
X-22441Y1488425D01*
G01X0Y1881654D02*
X-22441D01*
G01X0Y1879134D02*
X-22441D01*
G01X-23622Y1879724D02*
X-22441Y1879134D01*
G01D02*
Y1881654D01*
G01X-23622Y1879724D02*
Y1881063D01*
G01D02*
X-22441Y1881654D01*
G01X0Y1921654D02*
X-22441D01*
G01X0Y1919134D02*
X-22441D01*
G01X0Y1911654D02*
X-22441D01*
G01X0Y1909134D02*
X-22441D01*
G01X0Y1901654D02*
X-22441D01*
G01X0Y1899134D02*
X-22441D01*
G01X0Y1891654D02*
X-22441D01*
G01X0Y1889134D02*
X-22441D01*
G01X-23622Y1919724D02*
X-22441Y1919134D01*
G01X-23622Y1909724D02*
X-22441Y1909134D01*
G01X-23622Y1899724D02*
X-22441Y1899134D01*
G01X-23622Y1889724D02*
X-22441Y1889134D01*
G01Y1919134D02*
Y1921654D01*
G01Y1909134D02*
Y1911654D01*
G01Y1899134D02*
Y1901654D01*
G01Y1889134D02*
Y1891654D01*
G01X-23622Y1919724D02*
Y1921063D01*
G01Y1909724D02*
Y1911063D01*
G01Y1899724D02*
Y1901063D01*
G01Y1889724D02*
Y1891063D01*
G01D02*
X-22441Y1891654D01*
G01X-23622Y1901063D02*
X-22441Y1901654D01*
G01X-23622Y1911063D02*
X-22441Y1911654D01*
G01X-23622Y1921063D02*
X-22441Y1921654D01*
G01X18947Y-77963D02*
X19799Y-79288D01*
X20936Y-80046D01*
X22214Y-80235D01*
X23350Y-80046D01*
X24487Y-79099D01*
X25197Y-77963D01*
X25339Y-76826D01*
X25055Y-75501D01*
X24060Y-74554D01*
X23066Y-74175D01*
X21788D01*
G01X23066D02*
X23918Y-73607D01*
X24629Y-72661D01*
X24913Y-71524D01*
X24629Y-70388D01*
X23918Y-69441D01*
X22640Y-68873D01*
X21362Y-69062D01*
X20084Y-69820D01*
G01X37008Y24803D02*
G03I-7087J0D01*
G01X0Y3937D02*
G03X3937Y0I3937J0D01*
G01X0Y3937D02*
Y43110D01*
G01X64961Y0D02*
X3937D01*
G01X0Y3937D02*
G03X3937Y0I3937J0D01*
G01X0Y3937D02*
G03X3937Y0I3937J0D01*
G01X0Y3937D02*
Y43110D01*
G01Y3937D02*
Y43110D01*
G01X64961Y0D02*
X3937D01*
G01X64961D02*
X3937D01*
G01X0Y1964567D02*
Y3937D01*
G01X-7874D02*
Y1964567D01*
G01X0Y11811D02*
G03X-7874I-3937J0D01*
G01Y42520D02*
G03X0I3937J0D01*
G01Y1964567D02*
Y3937D01*
G01X-7874D02*
Y1964567D01*
G01X0Y11811D02*
G03X-7874I-3937J0D01*
G01Y42520D02*
G03X0I3937J0D01*
G01X-11811Y0D02*
G03X-7874Y3937I0J3937D01*
G01X-11811Y0D02*
G03X-7874Y3937I0J3937D01*
G01X0D02*
G03X3937Y0I3937J0D01*
G01X0Y3937D02*
G03X3937Y0I3937J0D01*
G01X64961D02*
X3937D01*
G01X64961D02*
X3937D01*
G01X0Y3937D02*
G03X3937Y0I3937J0D01*
G01D02*
X64961D01*
G01X-11811D02*
G03X-7874Y3937I0J3937D01*
G01X0D02*
G03X3937Y0I3937J0D01*
G01D02*
X64961D01*
G01X-11811D02*
G03X-7874Y3937I0J3937D01*
G01X13907Y49370D02*
G03Y46850I1998J-1260D01*
G01Y59370D02*
G03Y56850I1998J-1260D01*
G01Y69370D02*
G03Y66850I1998J-1260D01*
G01Y79370D02*
G03Y76850I1998J-1260D01*
G01Y89370D02*
G03Y86850I1998J-1260D01*
G01X19004Y88082D02*
X18878Y88041D01*
G01Y88287D02*
X19004Y88328D01*
G01X18711Y88164D02*
X18878Y88287D01*
G01X16575Y48780D02*
X17165Y49370D01*
G01X15236Y47441D02*
X14646Y46850D01*
G01X18878Y88041D02*
X18795Y87959D01*
G01X16575Y58780D02*
X17165Y59370D01*
G01X15236Y57441D02*
X14646Y56850D01*
G01X16575Y68780D02*
X17165Y69370D01*
G01X15236Y67441D02*
X14646Y66850D01*
G01X16575Y78780D02*
X17165Y79370D01*
G01X15236Y77441D02*
X14646Y76850D01*
G01X16575Y88780D02*
X17165Y89370D01*
G01X15236Y87441D02*
X14646Y86850D01*
G01X18585Y88000D02*
X18711Y88164D01*
G01X18795Y87959D02*
X18753Y87836D01*
G01X18543Y87795D02*
X18585Y88000D01*
G01X20512Y87057D02*
Y86811D01*
G01Y89149D02*
Y88903D01*
G01X19632Y87795D02*
Y87057D01*
G01X19381D02*
Y87836D01*
G01X18753D02*
Y87057D01*
G01X18543Y88903D02*
Y89149D01*
G01Y86811D02*
Y87795D01*
G01X17165Y49370D02*
Y46850D01*
G01Y59370D02*
Y56850D01*
G01Y69370D02*
Y66850D01*
G01Y79370D02*
Y76850D01*
G01Y89370D02*
Y86850D01*
G01X16575Y87441D02*
Y88780D01*
G01Y77441D02*
Y78780D01*
G01Y67441D02*
Y68780D01*
G01Y57441D02*
Y58780D01*
G01Y47441D02*
Y48780D01*
G01X15236Y87441D02*
Y88780D01*
G01Y77441D02*
Y78780D01*
G01Y67441D02*
Y68780D01*
G01Y57441D02*
Y58780D01*
G01Y47441D02*
Y48780D01*
G01X14646Y49370D02*
Y46850D01*
G01Y59370D02*
Y56850D01*
G01Y69370D02*
Y66850D01*
G01Y79370D02*
Y76850D01*
G01Y89370D02*
Y86850D01*
G01X13661Y49370D02*
Y46850D01*
G01Y59370D02*
Y56850D01*
G01Y69370D02*
Y66850D01*
G01Y79370D02*
Y76850D01*
G01Y89370D02*
Y86850D01*
G01X10000Y43110D02*
Y93110D01*
G01X8819D02*
Y43110D01*
G01X0D02*
Y93110D01*
G01Y43110D02*
Y93110D01*
G01Y43110D02*
Y93110D01*
G01X19590Y88000D02*
X19632Y87795D01*
G01X19381Y87836D02*
X19339Y87959D01*
G01X19465Y88164D02*
X19590Y88000D01*
G01X15236Y88780D02*
X14646Y89370D01*
G01X17165Y86850D02*
X16575Y87441D01*
G01X15236Y78780D02*
X14646Y79370D01*
G01X17165Y76850D02*
X16575Y77441D01*
G01X17165Y66850D02*
X16575Y67441D01*
G01X15236Y68780D02*
X14646Y69370D01*
G01X15236Y58780D02*
X14646Y59370D01*
G01X17165Y56850D02*
X16575Y57441D01*
G01X15236Y48780D02*
X14646Y49370D01*
G01X17165Y46850D02*
X16575Y47441D01*
G01X19339Y87959D02*
X19255Y88041D01*
G01X18878Y88903D02*
X19172Y88656D01*
G01X18836D02*
X18543Y88903D01*
G01X19297Y88287D02*
X19465Y88164D01*
G01X19172Y88328D02*
X19297Y88287D01*
G01X19255Y88041D02*
X19130Y88082D01*
G01X10000Y91535D02*
X0D01*
G01X10000Y89370D02*
X8819D01*
G01X17165D02*
X10000D01*
G01X18543Y89149D02*
X20512D01*
G01Y88903D02*
X18878D01*
G01X16575Y88780D02*
X15236D01*
G01X19172Y88656D02*
X18836D01*
G01X19004Y88328D02*
X19172D01*
G01X19130Y88082D02*
X19004D01*
G01X15236Y87441D02*
X16575D01*
G01X18753Y87057D02*
X19381D01*
G01X19632D02*
X20512D01*
G01X10000Y86850D02*
X8819D01*
G01X17165D02*
X10000D01*
G01X20512Y86811D02*
X18543D01*
G01X0Y84685D02*
X10000D01*
G01X0Y83898D02*
X10000D01*
G01Y82323D02*
X0D01*
G01X10000Y81535D02*
X0D01*
G01X10000Y79370D02*
X8819D01*
G01X17165D02*
X10000D01*
G01X16575Y78780D02*
X15236D01*
G01Y77441D02*
X16575D01*
G01X10000Y76850D02*
X8819D01*
G01X17165D02*
X10000D01*
G01X0Y74685D02*
X10000D01*
G01X0Y73898D02*
X10000D01*
G01Y72323D02*
X0D01*
G01X10000Y71535D02*
X0D01*
G01X10000Y69370D02*
X8819D01*
G01X17165D02*
X10000D01*
G01X16575Y68780D02*
X15236D01*
G01Y67441D02*
X16575D01*
G01X10000Y66850D02*
X8819D01*
G01X17165D02*
X10000D01*
G01X0Y64685D02*
X10000D01*
G01X0Y63898D02*
X10000D01*
G01Y62323D02*
X0D01*
G01X10000Y61535D02*
X0D01*
G01X10000Y59370D02*
X8819D01*
G01X17165D02*
X10000D01*
G01X16575Y58780D02*
X15236D01*
G01Y57441D02*
X16575D01*
G01X10000Y56850D02*
X8819D01*
G01X17165D02*
X10000D01*
G01X0Y54685D02*
X10000D01*
G01X0Y53898D02*
X10000D01*
G01Y52323D02*
X0D01*
G01X10000Y51535D02*
X0D01*
G01X10000Y49370D02*
X8819D01*
G01X17165D02*
X10000D01*
G01X16575Y48780D02*
X15236D01*
G01Y47441D02*
X16575D01*
G01X10000Y46850D02*
X8819D01*
G01X17165D02*
X10000D01*
G01X0Y44685D02*
X10000D01*
G01X0Y43898D02*
X10000D01*
G01X0Y43110D02*
X10000D01*
G01X0D02*
Y93110D01*
G01Y43110D02*
Y93110D01*
G01Y43110D02*
Y93110D01*
G01X37008Y111417D02*
G03I-7087J0D01*
G01X0Y93110D02*
Y214764D01*
G01Y93110D02*
X10000D01*
G01Y92323D02*
X0D01*
G01Y93110D02*
Y214764D01*
G01Y93110D02*
Y214764D01*
G01X35433Y157480D02*
G03I-7874J0D01*
G01X17879Y229882D02*
G03X17289Y229291I0J-590D01*
G01X17520Y212441D02*
G03X18110Y211850I591J0D01*
G01X17520Y217559D02*
G03X16929Y218150I-591J0D01*
G01X11417Y223583D02*
G03X11220Y223386I0J-197D01*
G01Y222047D02*
G03X11417Y221850I197J0D01*
G01Y219882D02*
G03X11220Y219685I0J-197D01*
G01Y218346D02*
G03X11417Y218150I197J1D01*
G01X-2953Y226969D02*
G03Y214764I0J-6103D01*
G01X16501Y225945D02*
X13189Y223583D01*
G01X28740Y227323D02*
X30315Y228898D01*
G01X30709Y229291D02*
X30315Y228898D01*
G01X28740Y215748D02*
X30315Y218583D01*
G01X30709Y219291D02*
X30315Y218583D01*
G01X11220Y225157D02*
X14134Y231850D01*
G01X32677D02*
Y234055D01*
G01Y221850D02*
Y229882D01*
G01Y211850D02*
Y219882D01*
G01Y207677D02*
Y209882D01*
G01Y211014D02*
Y210768D01*
G01X32283Y211850D02*
Y209882D01*
G01Y221850D02*
Y219882D01*
G01Y231850D02*
Y229882D01*
G01X31535Y211850D02*
Y209882D01*
G01Y221850D02*
Y219882D01*
G01Y231850D02*
Y229882D01*
G01X30709Y210768D02*
Y211014D01*
G01X30315Y228898D02*
Y232441D01*
G01Y218583D02*
Y223150D01*
G01Y219882D02*
Y221850D01*
G01Y209291D02*
Y212913D01*
G01Y211850D02*
Y209882D01*
G01Y231850D02*
Y229882D01*
G01X28740Y209291D02*
Y232441D01*
G01X27559Y227879D02*
Y214698D01*
G01X17520Y217559D02*
Y212441D01*
G01X17289Y229291D02*
Y225945D01*
G01X11417Y218150D02*
Y215943D01*
G01Y221850D02*
Y219882D01*
G01X11220Y228346D02*
Y214764D01*
G01Y228896D02*
Y214698D01*
G01X9843Y231299D02*
Y210433D01*
G01X7283Y228346D02*
Y214764D01*
G01X6496Y227756D02*
Y214764D01*
G01X5906Y207677D02*
Y234055D01*
G01X0Y226969D02*
Y342461D01*
G01Y214764D02*
Y226969D01*
G01Y214764D02*
Y226969D01*
G01X-2953Y214764D02*
Y226969D01*
G01X-5906Y226197D02*
Y215535D01*
G01X14055Y209882D02*
X11220Y216396D01*
G01X30315Y223150D02*
X28740Y225984D01*
G01X30315Y223150D02*
X30709Y222441D01*
G01X30315Y212913D02*
X30709Y212441D01*
G01X30315Y212913D02*
X28740Y214803D01*
G01X32384Y211260D02*
X32677Y211014D01*
G01X32342D02*
X32283Y211063D01*
G01D02*
X32049Y211260D01*
G01X5906Y234055D02*
X32677D01*
G01X28740Y232441D02*
X30315D01*
G01X32677D02*
X30315D01*
G01X5906Y232047D02*
X30315D01*
G01Y231850D02*
X32283D01*
G01X30315D02*
X14134D01*
G01X32677D02*
X32283D01*
G01D02*
X30315D01*
G01Y231299D02*
X9843D01*
G01X30315Y229882D02*
X32283D01*
G01X17879D02*
X30315D01*
G01X32677D02*
X32283D01*
G01D02*
X30315D01*
G01X32677Y229291D02*
X30709D01*
G01X11220Y228896D02*
X5906D01*
G01X7283Y228346D02*
X11220D01*
G01X27559Y227879D02*
X11220D01*
G01X6496Y227756D02*
X7283D01*
G01X5906Y226969D02*
X-2953D01*
G01X6496D02*
X5906D01*
G01X17289Y225945D02*
X16501D01*
G01X13189Y223583D02*
X11417D01*
G01X32677Y222441D02*
X30709D01*
G01X30315Y221850D02*
X32283D01*
G01X11417D02*
X30315D01*
G01X32677D02*
X32283D01*
G01D02*
X30315D01*
G01Y219882D02*
X11417D01*
G01X32283D02*
X30315D01*
G01X32677D02*
X32283D01*
G01D02*
X30315D01*
G01X32677Y219291D02*
X30709D01*
G01X11417Y218150D02*
X16929D01*
G01X5906Y214764D02*
X11220D01*
G01X5906D02*
X-2953D01*
G01X11220Y214724D02*
X5906D01*
G01X27559Y214698D02*
X11220D01*
G01X32677Y212441D02*
X30709D01*
G01X30315Y211850D02*
X32283D01*
G01X18110D02*
X30315D01*
G01X32677D02*
X32283D01*
G01D02*
X30315D01*
G01X32283Y211260D02*
X32384D01*
G01X32049D02*
X32283D01*
G01Y211014D02*
X32342D01*
G01X30709D02*
X32283D01*
G01X32677Y210768D02*
X32283D01*
G01D02*
X30709D01*
G01X30315Y210433D02*
X9843D01*
G01X30315Y209882D02*
X14055D01*
G01X32283D02*
X30315D01*
G01X32677D02*
X32283D01*
G01D02*
X30315D01*
G01X5906Y209685D02*
X30315D01*
G01X28740Y209291D02*
X30315D01*
G01X32677D02*
X30315D01*
G01X5906Y207677D02*
X32677D01*
G01X0Y226969D02*
Y342461D01*
G01Y226969D02*
Y342461D01*
G01Y214764D02*
Y226969D01*
G01Y214764D02*
Y226969D01*
G01Y214764D02*
Y226969D01*
G01Y214764D02*
Y226969D01*
G01Y278740D02*
G03X-7874I-3937J0D01*
G01X0D02*
G03X-7874I-3937J0D01*
G01X17520Y340138D02*
G03X18110Y339547I591J0D01*
G01X17520Y345256D02*
G03X16929Y345846I-590J0D01*
G01X11417Y347579D02*
G03X11220Y347382I0J-197D01*
G01Y346043D02*
G03X11417Y345846I197J0D01*
G01X-2953Y354665D02*
G03Y342461I0J-6102D01*
G01X28740Y343445D02*
X30315Y346280D01*
G01X30709Y346988D02*
X30315Y346280D01*
G01X32677Y339547D02*
Y347579D01*
G01Y335374D02*
Y337579D01*
G01Y338711D02*
Y338465D01*
G01X32283Y339547D02*
Y337579D01*
G01X31535Y339547D02*
Y337579D01*
G01X30709Y338465D02*
Y338711D01*
G01X30315Y346280D02*
Y350846D01*
G01Y336988D02*
Y340610D01*
G01Y339547D02*
Y337579D01*
G01X28740Y336988D02*
Y360138D01*
G01X27559Y355575D02*
Y342395D01*
G01X17520Y345256D02*
Y340138D01*
G01X11417Y345846D02*
Y343640D01*
G01X11220Y356593D02*
Y342395D01*
G01Y356043D02*
Y342461D01*
G01X9843Y358996D02*
Y338130D01*
G01X7283Y356043D02*
Y342461D01*
G01X6496Y355453D02*
Y342461D01*
G01X5906Y335374D02*
Y361752D01*
G01X0Y342461D02*
Y354665D01*
G01Y342461D02*
Y354665D01*
G01X-2953Y342461D02*
Y354665D01*
G01X-5906Y353894D02*
Y343232D01*
G01X14055Y337579D02*
X11220Y344093D01*
G01X30315Y340610D02*
X30709Y340138D01*
G01X30315Y340610D02*
X28740Y342500D01*
G01X32384Y338957D02*
X32677Y338711D01*
G01X32342D02*
X32283Y338760D01*
G01D02*
X32049Y338957D01*
G01X32677Y346988D02*
X30709D01*
G01X11417Y345846D02*
X16929D01*
G01X5906Y342461D02*
X11220D01*
G01X5906D02*
X-2953D01*
G01X11220Y342421D02*
X5906D01*
G01X27559Y342395D02*
X11220D01*
G01X32677Y340138D02*
X30709D01*
G01X30315Y339547D02*
X32283D01*
G01X18110D02*
X30315D01*
G01X32677D02*
X32283D01*
G01D02*
X30315D01*
G01X32283Y338957D02*
X32384D01*
G01X32049D02*
X32283D01*
G01Y338711D02*
X32342D01*
G01X30709D02*
X32283D01*
G01X32677Y338465D02*
X32283D01*
G01D02*
X30709D01*
G01X30315Y338130D02*
X9843D01*
G01X30315Y337579D02*
X14055D01*
G01X32283D02*
X30315D01*
G01X32677D02*
X32283D01*
G01D02*
X30315D01*
G01X5906Y337382D02*
X30315D01*
G01X28740Y336988D02*
X30315D01*
G01X32677D02*
X30315D01*
G01X5906Y335374D02*
X32677D01*
G01X0Y342461D02*
Y354665D01*
G01Y342461D02*
Y354665D01*
G01X-7874Y309449D02*
G03X0I3937J0D01*
G01X-7874D02*
G03X0I3937J0D01*
G01X17879Y357579D02*
G03X17289Y356988I1J-591D01*
G01X11417Y351280D02*
G03X11220Y351083I0J-197D01*
G01Y349744D02*
G03X11417Y349547I197J0D01*
G01X16501Y353642D02*
X13189Y351280D01*
G01X28740Y355020D02*
X30315Y356594D01*
G01X30709Y356988D02*
X30315Y356594D01*
G01X11220Y352854D02*
X14134Y359547D01*
G01X32677D02*
Y361752D01*
G01Y349547D02*
Y357579D01*
G01X32283Y349547D02*
Y347579D01*
G01Y359547D02*
Y357579D01*
G01X31535Y349547D02*
Y347579D01*
G01Y359547D02*
Y357579D01*
G01X30315Y356594D02*
Y360138D01*
G01Y347579D02*
Y349547D01*
G01Y359547D02*
Y357579D01*
G01X17289Y356988D02*
Y353642D01*
G01X11417Y349547D02*
Y347579D01*
G01X0Y354665D02*
Y476339D01*
G01X30315Y350846D02*
X28740Y353681D01*
G01X30315Y350846D02*
X30709Y350138D01*
G01X5906Y361752D02*
X32677D01*
G01X28740Y360138D02*
X30315D01*
G01X32677D02*
X30315D01*
G01X5906Y359744D02*
X30315D01*
G01Y359547D02*
X32283D01*
G01X30315D02*
X14134D01*
G01X32677D02*
X32283D01*
G01D02*
X30315D01*
G01Y358996D02*
X9843D01*
G01X30315Y357579D02*
X32283D01*
G01X17879D02*
X30315D01*
G01X32677D02*
X32283D01*
G01D02*
X30315D01*
G01X32677Y356988D02*
X30709D01*
G01X11220Y356593D02*
X5906D01*
G01X7283Y356043D02*
X11220D01*
G01X27559Y355575D02*
X11220D01*
G01X6496Y355453D02*
X7283D01*
G01X5906Y354665D02*
X-2953D01*
G01X6496D02*
X5906D01*
G01X17289Y353642D02*
X16501D01*
G01X13189Y351280D02*
X11417D01*
G01X32677Y350138D02*
X30709D01*
G01X30315Y349547D02*
X32283D01*
G01X11417D02*
X30315D01*
G01X32677D02*
X32283D01*
G01D02*
X30315D01*
G01Y347579D02*
X11417D01*
G01X32283D02*
X30315D01*
G01X32677D02*
X32283D01*
G01D02*
X30315D01*
G01X0Y354665D02*
Y476339D01*
G01Y354665D02*
Y476339D01*
G01X13907Y482598D02*
G03Y480079I1998J-1259D01*
G01Y492598D02*
G03Y490079I1998J-1260D01*
G01Y502598D02*
G03Y500079I1998J-1259D01*
G01X37008Y458032D02*
G03I-7087J0D01*
G01X16575Y482008D02*
X17165Y482598D01*
G01X15236Y480669D02*
X14646Y480079D01*
G01X16575Y492008D02*
X17165Y492598D01*
G01X15236Y490669D02*
X14646Y490079D01*
G01X15236Y500669D02*
X14646Y500079D01*
G01X17165Y482598D02*
Y480079D01*
G01Y492598D02*
Y490079D01*
G01Y502598D02*
Y500079D01*
G01X16575Y500669D02*
Y502008D01*
G01Y490669D02*
Y492008D01*
G01Y480669D02*
Y482008D01*
G01X15236Y500669D02*
Y502008D01*
G01Y490669D02*
Y492008D01*
G01Y480669D02*
Y482008D01*
G01X14646Y482598D02*
Y480079D01*
G01Y492598D02*
Y490079D01*
G01Y502598D02*
Y500079D01*
G01X13661Y482598D02*
Y480079D01*
G01Y492598D02*
Y490079D01*
G01Y502598D02*
Y500079D01*
G01X10000Y476339D02*
Y526339D01*
G01X8819D02*
Y476339D01*
G01X0D02*
Y526339D01*
G01Y476339D02*
Y526339D01*
G01Y476339D02*
Y526339D01*
G01X17165Y500079D02*
X16575Y500669D01*
G01X15236Y492008D02*
X14646Y492598D01*
G01X17165Y490079D02*
X16575Y490669D01*
G01X15236Y482008D02*
X14646Y482598D01*
G01X17165Y480079D02*
X16575Y480669D01*
G01X15236Y500669D02*
X16575D01*
G01X10000Y500079D02*
X8819D01*
G01X17165D02*
X10000D01*
G01X0Y497913D02*
X10000D01*
G01X0Y497126D02*
X10000D01*
G01Y495551D02*
X0D01*
G01X10000Y494764D02*
X0D01*
G01X10000Y492598D02*
X8819D01*
G01X17165D02*
X10000D01*
G01X16575Y492008D02*
X15236D01*
G01Y490669D02*
X16575D01*
G01X10000Y490079D02*
X8819D01*
G01X17165D02*
X10000D01*
G01X0Y487913D02*
X10000D01*
G01X0Y487126D02*
X10000D01*
G01Y485551D02*
X0D01*
G01X10000Y484764D02*
X0D01*
G01X10000Y482598D02*
X8819D01*
G01X17165D02*
X10000D01*
G01X16575Y482008D02*
X15236D01*
G01Y480669D02*
X16575D01*
G01X10000Y480079D02*
X8819D01*
G01X17165D02*
X10000D01*
G01X0Y477913D02*
X10000D01*
G01X0Y477126D02*
X10000D01*
G01X0Y476339D02*
X10000D01*
G01X0D02*
Y526339D01*
G01Y476339D02*
Y526339D01*
G01Y476339D02*
Y526339D01*
G01X13907Y512598D02*
G03Y510079I1998J-1259D01*
G01Y522598D02*
G03Y520079I1998J-1259D01*
G01X37008Y544646D02*
G03I-7087J0D01*
G01X19004Y521311D02*
X18878Y521270D01*
G01Y521516D02*
X19004Y521557D01*
G01X18711Y521393D02*
X18878Y521516D01*
G01Y521270D02*
X18795Y521188D01*
G01X16575Y502008D02*
X17165Y502598D01*
G01X16575Y512008D02*
X17165Y512598D01*
G01X15236Y510669D02*
X14646Y510079D01*
G01X16575Y522008D02*
X17165Y522598D01*
G01X15236Y520669D02*
X14646Y520079D01*
G01X18585Y521229D02*
X18711Y521393D01*
G01X18795Y521188D02*
X18753Y521065D01*
G01X18543Y521024D02*
X18585Y521229D01*
G01X20512Y520285D02*
Y520039D01*
G01Y522377D02*
Y522131D01*
G01X19632Y521024D02*
Y520285D01*
G01X19381D02*
Y521065D01*
G01X18753D02*
Y520285D01*
G01X18543Y522131D02*
Y522377D01*
G01Y520039D02*
Y521024D01*
G01X17165Y512598D02*
Y510079D01*
G01Y522598D02*
Y520079D01*
G01X16575Y520669D02*
Y522008D01*
G01Y510669D02*
Y512008D01*
G01X15236Y520669D02*
Y522008D01*
G01Y510669D02*
Y512008D01*
G01X14646Y512598D02*
Y510079D01*
G01Y522598D02*
Y520079D01*
G01X13661Y512598D02*
Y510079D01*
G01Y522598D02*
Y520079D01*
G01X0Y526339D02*
Y736181D01*
G01X19590Y521229D02*
X19632Y521024D01*
G01X19381Y521065D02*
X19339Y521188D01*
G01X19465Y521393D02*
X19590Y521229D01*
G01X15236Y522008D02*
X14646Y522598D01*
G01X17165Y520079D02*
X16575Y520669D01*
G01X19339Y521188D02*
X19255Y521270D01*
G01X15236Y512008D02*
X14646Y512598D01*
G01X17165Y510079D02*
X16575Y510669D01*
G01X15236Y502008D02*
X14646Y502598D01*
G01X18878Y522131D02*
X19172Y521885D01*
G01X18836D02*
X18543Y522131D01*
G01X19297Y521516D02*
X19465Y521393D01*
G01X19172Y521557D02*
X19297Y521516D01*
G01X19255Y521270D02*
X19130Y521311D01*
G01X0Y526339D02*
X10000D01*
G01Y525551D02*
X0D01*
G01X10000Y524764D02*
X0D01*
G01X10000Y522598D02*
X8819D01*
G01X17165D02*
X10000D01*
G01X18543Y522377D02*
X20512D01*
G01Y522131D02*
X18878D01*
G01X16575Y522008D02*
X15236D01*
G01X19172Y521885D02*
X18836D01*
G01X19004Y521557D02*
X19172D01*
G01X19130Y521311D02*
X19004D01*
G01X15236Y520669D02*
X16575D01*
G01X18753Y520285D02*
X19381D01*
G01X19632D02*
X20512D01*
G01X10000Y520079D02*
X8819D01*
G01X17165D02*
X10000D01*
G01X20512Y520039D02*
X18543D01*
G01X0Y517913D02*
X10000D01*
G01X0Y517126D02*
X10000D01*
G01Y515551D02*
X0D01*
G01X10000Y514764D02*
X0D01*
G01X10000Y512598D02*
X8819D01*
G01X17165D02*
X10000D01*
G01X16575Y512008D02*
X15236D01*
G01Y510669D02*
X16575D01*
G01X10000Y510079D02*
X8819D01*
G01X17165D02*
X10000D01*
G01X0Y507913D02*
X10000D01*
G01X0Y507126D02*
X10000D01*
G01Y505551D02*
X0D01*
G01X10000Y504764D02*
X0D01*
G01X10000Y502598D02*
X8819D01*
G01X17165D02*
X10000D01*
G01X16575Y502008D02*
X15236D01*
G01X0Y526339D02*
Y736181D01*
G01Y526339D02*
Y736181D01*
G01Y545669D02*
G03X-7874I-3937J0D01*
G01X0D02*
G03X-7874I-3937J0D01*
G01Y576378D02*
G03X0I3937J0D01*
G01X-7874D02*
G03X0I3937J0D01*
G01X34449Y629921D02*
G03I-6890J0D01*
G01X13907Y742441D02*
G03Y739921I1998J-1260D01*
G01Y752441D02*
G03Y749921I1998J-1260D01*
G01X37008Y717874D02*
G03I-7087J0D01*
G01X16575Y741850D02*
X17165Y742441D01*
G01X15236Y740512D02*
X14646Y739921D01*
G01X16575Y751850D02*
X17165Y752441D01*
G01X15236Y750512D02*
X14646Y749921D01*
G01X17165Y742441D02*
Y739921D01*
G01Y752441D02*
Y749921D01*
G01X16575Y750512D02*
Y751850D01*
G01Y740512D02*
Y741850D01*
G01X15236Y750512D02*
Y751850D01*
G01Y740512D02*
Y741850D01*
G01X14646Y742441D02*
Y739921D01*
G01Y752441D02*
Y749921D01*
G01X13661Y742441D02*
Y739921D01*
G01Y752441D02*
Y749921D01*
G01X10000Y736181D02*
Y786181D01*
G01X8819D02*
Y736181D01*
G01X0D02*
Y786181D01*
G01Y736181D02*
Y786181D01*
G01Y736181D02*
Y786181D01*
G01X15236Y751850D02*
X14646Y752441D01*
G01X17165Y749921D02*
X16575Y750512D01*
G01X15236Y741850D02*
X14646Y742441D01*
G01X17165Y739921D02*
X16575Y740512D01*
G01X10000Y755394D02*
X0D01*
G01X10000Y754606D02*
X0D01*
G01X10000Y752441D02*
X8819D01*
G01X17165D02*
X10000D01*
G01X16575Y751850D02*
X15236D01*
G01Y750512D02*
X16575D01*
G01X10000Y749921D02*
X8819D01*
G01X17165D02*
X10000D01*
G01X0Y747756D02*
X10000D01*
G01X0Y746969D02*
X10000D01*
G01Y745394D02*
X0D01*
G01X10000Y744606D02*
X0D01*
G01X10000Y742441D02*
X8819D01*
G01X17165D02*
X10000D01*
G01X16575Y741850D02*
X15236D01*
G01Y740512D02*
X16575D01*
G01X10000Y739921D02*
X8819D01*
G01X17165D02*
X10000D01*
G01X0Y737756D02*
X10000D01*
G01X0Y736969D02*
X10000D01*
G01X0Y736181D02*
X10000D01*
G01X0D02*
Y786181D01*
G01Y736181D02*
Y786181D01*
G01Y736181D02*
Y786181D01*
G01X13907Y762441D02*
G03Y759921I1998J-1260D01*
G01Y772441D02*
G03Y769921I1998J-1260D01*
G01Y782441D02*
G03Y779921I1998J-1260D01*
G01X37008Y804488D02*
G03I-7087J0D01*
G01X19004Y781153D02*
X18878Y781112D01*
G01Y781358D02*
X19004Y781399D01*
G01X18711Y781235D02*
X18878Y781358D01*
G01Y781112D02*
X18795Y781030D01*
G01X16575Y761850D02*
X17165Y762441D01*
G01X15236Y760512D02*
X14646Y759921D01*
G01X16575Y771850D02*
X17165Y772441D01*
G01X15236Y770512D02*
X14646Y769921D01*
G01X16575Y781850D02*
X17165Y782441D01*
G01X15236Y780512D02*
X14646Y779921D01*
G01X18585Y781071D02*
X18711Y781235D01*
G01X18795Y781030D02*
X18753Y780907D01*
G01X18543Y780866D02*
X18585Y781071D01*
G01X19590D02*
X19632Y780866D01*
G01X20512Y782219D02*
Y781973D01*
G01Y780128D02*
Y779882D01*
G01X19632Y780866D02*
Y780128D01*
G01X19381D02*
Y780907D01*
G01X18753D02*
Y780128D01*
G01X18543Y781973D02*
Y782219D01*
G01Y779882D02*
Y780866D01*
G01X17165Y762441D02*
Y759921D01*
G01Y772441D02*
Y769921D01*
G01Y782441D02*
Y779921D01*
G01X16575Y780512D02*
Y781850D01*
G01Y770512D02*
Y771850D01*
G01Y760512D02*
Y761850D01*
G01X15236Y780512D02*
Y781850D01*
G01Y770512D02*
Y771850D01*
G01Y760512D02*
Y761850D01*
G01X14646Y762441D02*
Y759921D01*
G01Y772441D02*
Y769921D01*
G01Y782441D02*
Y779921D01*
G01X13661Y762441D02*
Y759921D01*
G01Y772441D02*
Y769921D01*
G01Y782441D02*
Y779921D01*
G01X0Y786181D02*
Y907815D01*
G01X19381Y780907D02*
X19339Y781030D01*
G01X19465Y781235D02*
X19590Y781071D01*
G01X15236Y781850D02*
X14646Y782441D01*
G01X17165Y779921D02*
X16575Y780512D01*
G01X15236Y771850D02*
X14646Y772441D01*
G01X17165Y769921D02*
X16575Y770512D01*
G01X17165Y759921D02*
X16575Y760512D01*
G01X15236Y761850D02*
X14646Y762441D01*
G01X19339Y781030D02*
X19255Y781112D01*
G01X18878Y781973D02*
X19172Y781727D01*
G01X18836D02*
X18543Y781973D01*
G01X19297Y781358D02*
X19465Y781235D01*
G01X19172Y781399D02*
X19297Y781358D01*
G01X19255Y781112D02*
X19130Y781153D01*
G01X0Y786181D02*
X10000D01*
G01Y785394D02*
X0D01*
G01X10000Y784606D02*
X0D01*
G01X10000Y782441D02*
X8819D01*
G01X17165D02*
X10000D01*
G01X18543Y782219D02*
X20512D01*
G01Y781973D02*
X18878D01*
G01X16575Y781850D02*
X15236D01*
G01X19172Y781727D02*
X18836D01*
G01X19004Y781399D02*
X19172D01*
G01X19130Y781153D02*
X19004D01*
G01X15236Y780512D02*
X16575D01*
G01X18753Y780128D02*
X19381D01*
G01X19632D02*
X20512D01*
G01X10000Y779921D02*
X8819D01*
G01X17165D02*
X10000D01*
G01X20512Y779882D02*
X18543D01*
G01X0Y777756D02*
X10000D01*
G01X0Y776969D02*
X10000D01*
G01Y775394D02*
X0D01*
G01X10000Y774606D02*
X0D01*
G01X10000Y772441D02*
X8819D01*
G01X17165D02*
X10000D01*
G01X16575Y771850D02*
X15236D01*
G01Y770512D02*
X16575D01*
G01X10000Y769921D02*
X8819D01*
G01X17165D02*
X10000D01*
G01X0Y767756D02*
X10000D01*
G01X0Y766969D02*
X10000D01*
G01Y765394D02*
X0D01*
G01X10000Y764606D02*
X0D01*
G01X10000Y762441D02*
X8819D01*
G01X17165D02*
X10000D01*
G01X16575Y761850D02*
X15236D01*
G01Y760512D02*
X16575D01*
G01X10000Y759921D02*
X8819D01*
G01X17165D02*
X10000D01*
G01X0Y757756D02*
X10000D01*
G01X0Y756969D02*
X10000D01*
G01X0Y786181D02*
Y907815D01*
G01Y786181D02*
Y907815D01*
G01X-7874Y862205D02*
G03X0I3937J0D01*
G01Y831496D02*
G03X-7874I-3937J0D01*
G01Y862205D02*
G03X0I3937J0D01*
G01Y831496D02*
G03X-7874I-3937J0D01*
G01X17520Y905492D02*
G03X18110Y904902I590J0D01*
G01X-2953Y920020D02*
G03Y907815I0J-6103D01*
G01X28740Y908799D02*
X30315Y911634D01*
G01X14055Y902933D02*
X11220Y909447D01*
G01X30315Y905965D02*
X28740Y907854D01*
G01X30315Y905965D02*
X30709Y905492D01*
G01X32384Y904311D02*
X32677Y904065D01*
G01X32342D02*
X32283Y904114D01*
G01D02*
X32049Y904311D01*
G01X5906Y907815D02*
X11220D01*
G01X5906D02*
X-2953D01*
G01X11220Y907776D02*
X5906D01*
G01X27559Y907749D02*
X11220D01*
G01X32677Y905492D02*
X30709D01*
G01X30315Y904902D02*
X32283D01*
G01X18110D02*
X30315D01*
G01X32677D02*
X32283D01*
G01D02*
X30315D01*
G01X32283Y904311D02*
X32384D01*
G01X32049D02*
X32283D01*
G01Y904065D02*
X32342D01*
G01X30709D02*
X32283D01*
G01X32677Y903819D02*
X32283D01*
G01D02*
X30709D01*
G01X30315Y903484D02*
X9843D01*
G01X30315Y902933D02*
X14055D01*
G01X32283D02*
X30315D01*
G01X32677D02*
X32283D01*
G01D02*
X30315D01*
G01X5906Y902736D02*
X30315D01*
G01X28740Y902343D02*
X30315D01*
G01X32677D02*
X30315D01*
G01X5906Y900728D02*
X32677D01*
G01Y904902D02*
Y912933D01*
G01Y900728D02*
Y902933D01*
G01Y904065D02*
Y903819D01*
G01X32283Y904902D02*
Y902933D01*
G01X31535Y904902D02*
Y902933D01*
G01X30709Y903819D02*
Y904065D01*
G01X30315Y902343D02*
Y905965D01*
G01Y904902D02*
Y902933D01*
G01X28740Y902343D02*
Y925492D01*
G01X27559Y920930D02*
Y907749D01*
G01X17520Y910610D02*
Y905492D01*
G01X11417Y911201D02*
Y908995D01*
G01X11220Y921947D02*
Y907749D01*
G01Y921398D02*
Y907815D01*
G01X9843Y924350D02*
Y903484D01*
G01X7283Y921398D02*
Y907815D01*
G01X6496Y920807D02*
Y907815D01*
G01X5906Y900728D02*
Y927106D01*
G01X0Y907815D02*
Y920020D01*
G01Y907815D02*
Y920020D01*
G01X-2953Y907815D02*
Y920020D01*
G01X-5906Y919248D02*
Y908587D01*
G01X0Y907815D02*
Y920020D01*
G01Y907815D02*
Y920020D01*
G01X17879Y922933D02*
G03X17289Y922343I0J-590D01*
G01X17520Y910610D02*
G03X16929Y911201I-591J0D01*
G01X11417Y916634D02*
G03X11220Y916437I0J-197D01*
G01Y915098D02*
G03X11417Y914902I197J1D01*
G01Y912933D02*
G03X11220Y912736I0J-197D01*
G01Y911398D02*
G03X11417Y911201I197J0D01*
G01X16501Y918996D02*
X13189Y916634D01*
G01X5906Y927106D02*
X32677D01*
G01X28740Y920374D02*
X30315Y921949D01*
G01X30709Y922343D02*
X30315Y921949D01*
G01X30709Y912343D02*
X30315Y911634D01*
G01X11220Y918209D02*
X14134Y924902D01*
G01X30315Y916201D02*
X28740Y919035D01*
G01X30315Y916201D02*
X30709Y915492D01*
G01X28740Y925492D02*
X30315D01*
G01X32677D02*
X30315D01*
G01X5906Y925098D02*
X30315D01*
G01Y924902D02*
X32283D01*
G01X30315D02*
X14134D01*
G01X32677D02*
X32283D01*
G01D02*
X30315D01*
G01Y924350D02*
X9843D01*
G01X30315Y922933D02*
X32283D01*
G01X17879D02*
X30315D01*
G01X32677D02*
X32283D01*
G01D02*
X30315D01*
G01X32677Y922343D02*
X30709D01*
G01X11220Y921947D02*
X5906D01*
G01X7283Y921398D02*
X11220D01*
G01X27559Y920930D02*
X11220D01*
G01X6496Y920807D02*
X7283D01*
G01X5906Y920020D02*
X-2953D01*
G01X6496D02*
X5906D01*
G01X17289Y918996D02*
X16501D01*
G01X13189Y916634D02*
X11417D01*
G01X32677Y915492D02*
X30709D01*
G01X30315Y914902D02*
X32283D01*
G01X11417D02*
X30315D01*
G01X32677D02*
X32283D01*
G01D02*
X30315D01*
G01Y912933D02*
X11417D01*
G01X32283D02*
X30315D01*
G01X32677D02*
X32283D01*
G01D02*
X30315D01*
G01X32677Y912343D02*
X30709D01*
G01X11417Y911201D02*
X16929D01*
G01X32677Y924902D02*
Y927106D01*
G01Y914902D02*
Y922933D01*
G01X32283Y914902D02*
Y912933D01*
G01Y924902D02*
Y922933D01*
G01X31535Y914902D02*
Y912933D01*
G01Y924902D02*
Y922933D01*
G01X30315Y921949D02*
Y925492D01*
G01Y911634D02*
Y916201D01*
G01Y912933D02*
Y914902D01*
G01Y924902D02*
Y922933D01*
G01X17289Y922343D02*
Y918996D01*
G01X11417Y914902D02*
Y912933D01*
G01X0Y920020D02*
Y1048484D01*
G01Y920020D02*
Y1048484D01*
G01Y920020D02*
Y1048484D01*
G01X17879Y1063602D02*
G03X17289Y1063012I0J-590D01*
G01X17520Y1046161D02*
G03X18110Y1045571I590J0D01*
G01X17520Y1051280D02*
G03X16929Y1051870I-591J-1D01*
G01X11417Y1057303D02*
G03X11220Y1057106I0J-197D01*
G01Y1055768D02*
G03X11417Y1055571I197J0D01*
G01Y1053602D02*
G03X11220Y1053406I0J-197D01*
G01Y1052067D02*
G03X11417Y1051870I197J0D01*
G01X-2953Y1060689D02*
G03Y1048484I0J-6103D01*
G01X30315Y1063602D02*
X32283D01*
G01X17879D02*
X30315D01*
G01X32677D02*
X32283D01*
G01D02*
X30315D01*
G01X32677Y1063012D02*
X30709D01*
G01X11220Y1062617D02*
X5906D01*
G01X7283Y1062067D02*
X11220D01*
G01X27559Y1061599D02*
X11220D01*
G01X6496Y1061476D02*
X7283D01*
G01X5906Y1060689D02*
X-2953D01*
G01X6496D02*
X5906D01*
G01X17289Y1059665D02*
X16501D01*
G01X13189Y1057303D02*
X11417D01*
G01X32677Y1056161D02*
X30709D01*
G01X30315Y1055571D02*
X32283D01*
G01X11417D02*
X30315D01*
G01X32677D02*
X32283D01*
G01D02*
X30315D01*
G01Y1053602D02*
X11417D01*
G01X32283D02*
X30315D01*
G01X32677D02*
X32283D01*
G01D02*
X30315D01*
G01X32677Y1053012D02*
X30709D01*
G01X11417Y1051870D02*
X16929D01*
G01X5906Y1048484D02*
X11220D01*
G01X5906D02*
X-2953D01*
G01X11220Y1048445D02*
X5906D01*
G01X27559Y1048418D02*
X11220D01*
G01X32677Y1046161D02*
X30709D01*
G01X30315Y1045571D02*
X32283D01*
G01X18110D02*
X30315D01*
G01X32677D02*
X32283D01*
G01D02*
X30315D01*
G01X32283Y1044980D02*
X32384D01*
G01X32049D02*
X32283D01*
G01Y1044734D02*
X32342D01*
G01X30709D02*
X32283D01*
G01X32677Y1044488D02*
X32283D01*
G01D02*
X30709D01*
G01X30315Y1044154D02*
X9843D01*
G01X30315Y1043602D02*
X14055D01*
G01X32283D02*
X30315D01*
G01X32677D02*
X32283D01*
G01D02*
X30315D01*
G01X5906Y1043406D02*
X30315D01*
G01X28740Y1043012D02*
X30315D01*
G01X32677D02*
X30315D01*
G01X5906Y1041398D02*
X32677D01*
G01X14055Y1043602D02*
X11220Y1050116D01*
G01X30315Y1056870D02*
X28740Y1059705D01*
G01X30315Y1056870D02*
X30709Y1056161D01*
G01X30315Y1046634D02*
X28740Y1048524D01*
G01X30315Y1046634D02*
X30709Y1046161D01*
G01X32384Y1044980D02*
X32677Y1044734D01*
G01X32342D02*
X32283Y1044783D01*
G01D02*
X32049Y1044980D01*
G01X16501Y1059665D02*
X13189Y1057303D01*
G01X28740Y1061043D02*
X30315Y1062618D01*
G01X30709Y1063012D02*
X30315Y1062618D01*
G01X28740Y1049469D02*
X30315Y1052303D01*
G01X30709Y1053012D02*
X30315Y1052303D01*
G01X11220Y1058878D02*
X14134Y1065571D01*
G01X32677Y1055571D02*
Y1063602D01*
G01Y1045571D02*
Y1053602D01*
G01Y1041398D02*
Y1043602D01*
G01Y1044734D02*
Y1044488D01*
G01X32283Y1045571D02*
Y1043602D01*
G01Y1055571D02*
Y1053602D01*
G01Y1065571D02*
Y1063602D01*
G01X31535Y1045571D02*
Y1043602D01*
G01Y1055571D02*
Y1053602D01*
G01Y1065571D02*
Y1063602D01*
G01X30709Y1044488D02*
Y1044734D01*
G01X30315Y1062618D02*
Y1066161D01*
G01Y1052303D02*
Y1056870D01*
G01Y1053602D02*
Y1055571D01*
G01Y1043012D02*
Y1046634D01*
G01Y1045571D02*
Y1043602D01*
G01Y1065571D02*
Y1063602D01*
G01X28740Y1043012D02*
Y1066161D01*
G01X27559Y1061599D02*
Y1048418D01*
G01X17520Y1051280D02*
Y1046161D01*
G01X17289Y1063012D02*
Y1059665D01*
G01X11417Y1051870D02*
Y1049664D01*
G01Y1055571D02*
Y1053602D01*
G01X11220Y1062067D02*
Y1048484D01*
G01Y1062617D02*
Y1048418D01*
G01X9843Y1065020D02*
Y1044154D01*
G01X7283Y1062067D02*
Y1048484D01*
G01X6496Y1061476D02*
Y1048484D01*
G01X5906Y1041398D02*
Y1067776D01*
G01X0Y1060689D02*
Y1182323D01*
G01Y1048484D02*
Y1060689D01*
G01Y1048484D02*
Y1060689D01*
G01X-2953Y1048484D02*
Y1060689D01*
G01X-5906Y1059917D02*
Y1049256D01*
G01X0Y1060689D02*
Y1182323D01*
G01Y1060689D02*
Y1182323D01*
G01Y1048484D02*
Y1060689D01*
G01Y1048484D02*
Y1060689D01*
G01X5906Y1067776D02*
X32677D01*
G01X28740Y1066161D02*
X30315D01*
G01X32677D02*
X30315D01*
G01X5906Y1065768D02*
X30315D01*
G01Y1065571D02*
X32283D01*
G01X30315D02*
X14134D01*
G01X32677D02*
X32283D01*
G01D02*
X30315D01*
G01Y1065020D02*
X9843D01*
G01X32677Y1065571D02*
Y1067776D01*
G01X0Y1106299D02*
G03X-7874I-3937J0D01*
G01X0D02*
G03X-7874I-3937J0D01*
G01X37008Y1164016D02*
G03I-7087J0D01*
G01X-7874Y1137008D02*
G03X0I3937J0D01*
G01X-7874D02*
G03X0I3937J0D01*
G01X13907Y1188583D02*
G03Y1186063I1998J-1260D01*
G01Y1198583D02*
G03Y1196063I1998J-1260D01*
G01Y1208583D02*
G03Y1206063I1998J-1260D01*
G01Y1218583D02*
G03Y1216063I1998J-1260D01*
G01X15236Y1216654D02*
X16575D01*
G01X10000Y1216063D02*
X8819D01*
G01X17165D02*
X10000D01*
G01X0Y1213898D02*
X10000D01*
G01X0Y1213110D02*
X10000D01*
G01Y1211535D02*
X0D01*
G01X10000Y1210748D02*
X0D01*
G01X10000Y1208583D02*
X8819D01*
G01X17165D02*
X10000D01*
G01X16575Y1207992D02*
X15236D01*
G01Y1206654D02*
X16575D01*
G01X10000Y1206063D02*
X8819D01*
G01X17165D02*
X10000D01*
G01X0Y1203898D02*
X10000D01*
G01X0Y1203110D02*
X10000D01*
G01Y1201535D02*
X0D01*
G01X10000Y1200748D02*
X0D01*
G01X10000Y1198583D02*
X8819D01*
G01X17165D02*
X10000D01*
G01X16575Y1197992D02*
X15236D01*
G01Y1196654D02*
X16575D01*
G01X10000Y1196063D02*
X8819D01*
G01X17165D02*
X10000D01*
G01X0Y1193898D02*
X10000D01*
G01X0Y1193110D02*
X10000D01*
G01Y1191535D02*
X0D01*
G01X10000Y1190748D02*
X0D01*
G01X10000Y1188583D02*
X8819D01*
G01X17165D02*
X10000D01*
G01X16575Y1187992D02*
X15236D01*
G01Y1186654D02*
X16575D01*
G01X10000Y1186063D02*
X8819D01*
G01X17165D02*
X10000D01*
G01X0Y1183898D02*
X10000D01*
G01X0Y1183110D02*
X10000D01*
G01X0Y1182323D02*
X10000D01*
G01X17165Y1216063D02*
X16575Y1216654D01*
G01X15236Y1207992D02*
X14646Y1208583D01*
G01X17165Y1206063D02*
X16575Y1206654D01*
G01X15236Y1197992D02*
X14646Y1198583D01*
G01X17165Y1196063D02*
X16575Y1196654D01*
G01X17165Y1186063D02*
X16575Y1186654D01*
G01X15236Y1187992D02*
X14646Y1188583D01*
G01X17165D02*
Y1186063D01*
G01Y1198583D02*
Y1196063D01*
G01Y1208583D02*
Y1206063D01*
G01Y1218583D02*
Y1216063D01*
G01X16575Y1216654D02*
Y1217992D01*
G01Y1206654D02*
Y1207992D01*
G01Y1196654D02*
Y1197992D01*
G01Y1186654D02*
Y1187992D01*
G01X15236Y1216654D02*
Y1217992D01*
G01Y1206654D02*
Y1207992D01*
G01Y1196654D02*
Y1197992D01*
G01Y1186654D02*
Y1187992D01*
G01X14646Y1188583D02*
Y1186063D01*
G01Y1198583D02*
Y1196063D01*
G01Y1208583D02*
Y1206063D01*
G01Y1218583D02*
Y1216063D01*
G01X13661Y1188583D02*
Y1186063D01*
G01Y1198583D02*
Y1196063D01*
G01Y1208583D02*
Y1206063D01*
G01Y1218583D02*
Y1216063D01*
G01X10000Y1182323D02*
Y1232323D01*
G01X8819D02*
Y1182323D01*
G01X0D02*
Y1232323D01*
G01Y1182323D02*
Y1232323D01*
G01Y1182323D02*
Y1232323D01*
G01X16575Y1187992D02*
X17165Y1188583D01*
G01X15236Y1186654D02*
X14646Y1186063D01*
G01X16575Y1197992D02*
X17165Y1198583D01*
G01X15236Y1196654D02*
X14646Y1196063D01*
G01X16575Y1207992D02*
X17165Y1208583D01*
G01X15236Y1206654D02*
X14646Y1206063D01*
G01X15236Y1216654D02*
X14646Y1216063D01*
G01X0Y1182323D02*
Y1232323D01*
G01Y1182323D02*
Y1232323D01*
G01Y1182323D02*
Y1232323D01*
G01X13907Y1228583D02*
G03Y1226063I1998J-1260D01*
G01X37008Y1250630D02*
G03I-7087J0D01*
G01X19172Y1227541D02*
X19297Y1227500D01*
G01X19255Y1227254D02*
X19130Y1227295D01*
G01X0Y1232323D02*
X10000D01*
G01Y1231535D02*
X0D01*
G01X10000Y1230748D02*
X0D01*
G01X10000Y1228583D02*
X8819D01*
G01X17165D02*
X10000D01*
G01X18543Y1228361D02*
X20512D01*
G01Y1228115D02*
X18878D01*
G01X16575Y1227992D02*
X15236D01*
G01X19172Y1227869D02*
X18836D01*
G01X19004Y1227541D02*
X19172D01*
G01X19130Y1227295D02*
X19004D01*
G01X15236Y1226654D02*
X16575D01*
G01X18753Y1226270D02*
X19381D01*
G01X19632D02*
X20512D01*
G01X10000Y1226063D02*
X8819D01*
G01X17165D02*
X10000D01*
G01X20512Y1226024D02*
X18543D01*
G01X0Y1223898D02*
X10000D01*
G01X0Y1223110D02*
X10000D01*
G01Y1221535D02*
X0D01*
G01X10000Y1220748D02*
X0D01*
G01X10000Y1218583D02*
X8819D01*
G01X17165D02*
X10000D01*
G01X16575Y1217992D02*
X15236D01*
G01X19297Y1227500D02*
X19465Y1227377D01*
G01D02*
X19590Y1227213D01*
G01X15236Y1227992D02*
X14646Y1228583D01*
G01X17165Y1226063D02*
X16575Y1226654D01*
G01X15236Y1217992D02*
X14646Y1218583D01*
G01X19339Y1227172D02*
X19255Y1227254D01*
G01X18878Y1228115D02*
X19172Y1227869D01*
G01X18836D02*
X18543Y1228115D01*
G01X19381Y1227049D02*
X19339Y1227172D01*
G01X19590Y1227213D02*
X19632Y1227008D01*
G01X18543D02*
X18585Y1227213D01*
G01X20512Y1226270D02*
Y1226024D01*
G01Y1228361D02*
Y1228115D01*
G01X19632Y1227008D02*
Y1226270D01*
G01X19381D02*
Y1227049D01*
G01X18753D02*
Y1226270D01*
G01X18543Y1228115D02*
Y1228361D01*
G01Y1226024D02*
Y1227008D01*
G01X17165Y1228583D02*
Y1226063D01*
G01X16575Y1226654D02*
Y1227992D01*
G01X15236Y1226654D02*
Y1227992D01*
G01X14646Y1228583D02*
Y1226063D01*
G01X13661Y1228583D02*
Y1226063D01*
G01X0Y1232323D02*
Y1442165D01*
G01X18795Y1227172D02*
X18753Y1227049D01*
G01X19004Y1227295D02*
X18878Y1227254D01*
G01Y1227500D02*
X19004Y1227541D01*
G01X18711Y1227377D02*
X18878Y1227500D01*
G01Y1227254D02*
X18795Y1227172D01*
G01X16575Y1217992D02*
X17165Y1218583D01*
G01X16575Y1227992D02*
X17165Y1228583D01*
G01X15236Y1226654D02*
X14646Y1226063D01*
G01X18585Y1227213D02*
X18711Y1227377D01*
G01X0Y1232323D02*
Y1442165D01*
G01Y1232323D02*
Y1442165D01*
G01X24606Y1338583D02*
G03I-6889J0D01*
G01X37008Y1423858D02*
G03I-7087J0D01*
G01X-7874Y1422835D02*
G03X0I3937J0D01*
G01Y1392126D02*
G03X-7874I-3937J0D01*
G01Y1422835D02*
G03X0I3937J0D01*
G01Y1392126D02*
G03X-7874I-3937J0D01*
G01X13907Y1448425D02*
G03Y1445905I1998J-1260D01*
G01Y1458425D02*
G03Y1455905I1998J-1260D01*
G01Y1468425D02*
G03Y1465905I1998J-1260D01*
G01X0Y1472953D02*
X10000D01*
G01Y1471378D02*
X0D01*
G01X10000Y1470591D02*
X0D01*
G01X10000Y1468425D02*
X8819D01*
G01X17165D02*
X10000D01*
G01X16575Y1467835D02*
X15236D01*
G01Y1466496D02*
X16575D01*
G01X10000Y1465906D02*
X8819D01*
G01X17165D02*
X10000D01*
G01X0Y1463740D02*
X10000D01*
G01X0Y1462953D02*
X10000D01*
G01Y1461378D02*
X0D01*
G01X10000Y1460591D02*
X0D01*
G01X10000Y1458425D02*
X8819D01*
G01X17165D02*
X10000D01*
G01X16575Y1457835D02*
X15236D01*
G01Y1456496D02*
X16575D01*
G01X10000Y1455906D02*
X8819D01*
G01X17165D02*
X10000D01*
G01X0Y1453740D02*
X10000D01*
G01X0Y1452953D02*
X10000D01*
G01Y1451378D02*
X0D01*
G01X10000Y1450591D02*
X0D01*
G01X10000Y1448425D02*
X8819D01*
G01X17165D02*
X10000D01*
G01X16575Y1447835D02*
X15236D01*
G01Y1446496D02*
X16575D01*
G01X10000Y1445906D02*
X8819D01*
G01X17165D02*
X10000D01*
G01X0Y1443740D02*
X10000D01*
G01X0Y1442953D02*
X10000D01*
G01X0Y1442165D02*
X10000D01*
G01X15236Y1467835D02*
X14646Y1468425D01*
G01X17165Y1465906D02*
X16575Y1466496D01*
G01X15236Y1457835D02*
X14646Y1458425D01*
G01X17165Y1455906D02*
X16575Y1456496D01*
G01X15236Y1447835D02*
X14646Y1448425D01*
G01X17165Y1445906D02*
X16575Y1446496D01*
G01X17165Y1448425D02*
Y1445906D01*
G01Y1458425D02*
Y1455906D01*
G01Y1468425D02*
Y1465906D01*
G01X16575Y1466496D02*
Y1467835D01*
G01Y1456496D02*
Y1457835D01*
G01Y1446496D02*
Y1447835D01*
G01X15236Y1466496D02*
Y1467835D01*
G01Y1456496D02*
Y1457835D01*
G01Y1446496D02*
Y1447835D01*
G01X14646Y1448425D02*
Y1445906D01*
G01Y1458425D02*
Y1455906D01*
G01Y1468425D02*
Y1465906D01*
G01X13661Y1448425D02*
Y1445906D01*
G01Y1458425D02*
Y1455906D01*
G01Y1468425D02*
Y1465906D01*
G01X10000Y1442165D02*
Y1492165D01*
G01X8819D02*
Y1442165D01*
G01X0D02*
Y1492165D01*
G01Y1442165D02*
Y1492165D01*
G01Y1442165D02*
Y1492165D01*
G01X16575Y1447835D02*
X17165Y1448425D01*
G01X15236Y1446496D02*
X14646Y1445906D01*
G01X16575Y1457835D02*
X17165Y1458425D01*
G01X15236Y1456496D02*
X14646Y1455906D01*
G01X16575Y1467835D02*
X17165Y1468425D01*
G01X15236Y1466496D02*
X14646Y1465906D01*
G01X0Y1442165D02*
Y1492165D01*
G01Y1442165D02*
Y1492165D01*
G01Y1442165D02*
Y1492165D01*
G01Y1442165D02*
Y1492165D01*
G01Y1442165D02*
Y1492165D01*
G01X37008Y1510472D02*
G03I-7087J0D01*
G01X13907Y1478425D02*
G03Y1475905I1998J-1260D01*
G01Y1488425D02*
G03Y1485905I1998J-1260D01*
G01X0Y1492165D02*
X10000D01*
G01Y1491378D02*
X0D01*
G01X10000Y1490591D02*
X0D01*
G01X10000Y1488425D02*
X8819D01*
G01X17165D02*
X10000D01*
G01X18543Y1488204D02*
X20512D01*
G01Y1487958D02*
X18878D01*
G01X16575Y1487835D02*
X15236D01*
G01X19172Y1487712D02*
X18836D01*
G01X19004Y1487384D02*
X19172D01*
G01X19130Y1487137D02*
X19004D01*
G01X15236Y1486496D02*
X16575D01*
G01X18753Y1486112D02*
X19381D01*
G01X19632D02*
X20512D01*
G01X10000Y1485906D02*
X8819D01*
G01X17165D02*
X10000D01*
G01X20512Y1485866D02*
X18543D01*
G01X0Y1483740D02*
X10000D01*
G01X0Y1482953D02*
X10000D01*
G01Y1481378D02*
X0D01*
G01X10000Y1480591D02*
X0D01*
G01X10000Y1478425D02*
X8819D01*
G01X17165D02*
X10000D01*
G01X16575Y1477835D02*
X15236D01*
G01Y1476496D02*
X16575D01*
G01X10000Y1475906D02*
X8819D01*
G01X17165D02*
X10000D01*
G01X0Y1473740D02*
X10000D01*
G01X19172Y1487384D02*
X19297Y1487343D01*
G01X19255Y1487096D02*
X19130Y1487137D01*
G01X19297Y1487343D02*
X19465Y1487219D01*
G01X15236Y1487835D02*
X14646Y1488425D01*
G01X17165Y1485906D02*
X16575Y1486496D01*
G01X15236Y1477835D02*
X14646Y1478425D01*
G01X17165Y1475906D02*
X16575Y1476496D01*
G01X19339Y1487014D02*
X19255Y1487096D01*
G01X18878Y1487958D02*
X19172Y1487712D01*
G01X18836D02*
X18543Y1487958D01*
G01X19465Y1487219D02*
X19590Y1487055D01*
G01X19381Y1486891D02*
X19339Y1487014D01*
G01X19590Y1487055D02*
X19632Y1486850D01*
G01X20512Y1488204D02*
Y1487958D01*
G01Y1486112D02*
Y1485866D01*
G01X19632Y1486850D02*
Y1486112D01*
G01X19381D02*
Y1486891D01*
G01X18753D02*
Y1486112D01*
G01X18543Y1487958D02*
Y1488204D01*
G01Y1485866D02*
Y1486850D01*
G01X17165Y1478425D02*
Y1475906D01*
G01Y1488425D02*
Y1485906D01*
G01X16575Y1486496D02*
Y1487835D01*
G01Y1476496D02*
Y1477835D01*
G01X15236Y1486496D02*
Y1487835D01*
G01Y1476496D02*
Y1477835D01*
G01X14646Y1478425D02*
Y1475906D01*
G01Y1488425D02*
Y1485906D01*
G01X13661Y1478425D02*
Y1475906D01*
G01Y1488425D02*
Y1485906D01*
G01X0Y1492165D02*
Y1613839D01*
G01X18543Y1486850D02*
X18585Y1487055D01*
G01X18795Y1487014D02*
X18753Y1486891D01*
G01X18585Y1487055D02*
X18711Y1487219D01*
G01D02*
X18878Y1487343D01*
G01Y1487096D02*
X18795Y1487014D01*
G01X16575Y1477835D02*
X17165Y1478425D01*
G01X15236Y1476496D02*
X14646Y1475906D01*
G01X16575Y1487835D02*
X17165Y1488425D01*
G01X15236Y1486496D02*
X14646Y1485906D01*
G01X19004Y1487137D02*
X18878Y1487096D01*
G01Y1487343D02*
X19004Y1487384D01*
G01X0Y1492165D02*
Y1613839D01*
G01Y1492165D02*
Y1613839D01*
G01X17520Y1611516D02*
G03X18110Y1610925I591J0D01*
G01X17520Y1616634D02*
G03X16929Y1617224I-591J-1D01*
G01X11417Y1622657D02*
G03X11220Y1622461I0J-197D01*
G01Y1621122D02*
G03X11417Y1620925I197J0D01*
G01Y1618957D02*
G03X11220Y1618760I0J-197D01*
G01Y1617421D02*
G03X11417Y1617224I197J0D01*
G01X-2953Y1626043D02*
G03Y1613839I0J-6102D01*
G01X5906Y1626043D02*
X-2953D01*
G01X6496D02*
X5906D01*
G01X17289Y1625020D02*
X16501D01*
G01X13189Y1622657D02*
X11417D01*
G01X32677Y1621516D02*
X30709D01*
G01X30315Y1620925D02*
X32283D01*
G01X11417D02*
X30315D01*
G01X32677D02*
X32283D01*
G01D02*
X30315D01*
G01Y1618957D02*
X11417D01*
G01X32283D02*
X30315D01*
G01X32677D02*
X32283D01*
G01D02*
X30315D01*
G01X32677Y1618366D02*
X30709D01*
G01X11417Y1617224D02*
X16929D01*
G01X5906Y1613839D02*
X11220D01*
G01X5906D02*
X-2953D01*
G01X11220Y1613799D02*
X5906D01*
G01X27559Y1613773D02*
X11220D01*
G01X32677Y1611516D02*
X30709D01*
G01X30315Y1610925D02*
X32283D01*
G01X18110D02*
X30315D01*
G01X32677D02*
X32283D01*
G01D02*
X30315D01*
G01X32283Y1610335D02*
X32384D01*
G01X32049D02*
X32283D01*
G01Y1610089D02*
X32342D01*
G01X30709D02*
X32283D01*
G01X32677Y1609843D02*
X32283D01*
G01D02*
X30709D01*
G01X30315Y1609508D02*
X9843D01*
G01X30315Y1608957D02*
X14055D01*
G01X32283D02*
X30315D01*
G01X32677D02*
X32283D01*
G01D02*
X30315D01*
G01X5906Y1608760D02*
X30315D01*
G01X28740Y1608366D02*
X30315D01*
G01X32677D02*
X30315D01*
G01X5906Y1606752D02*
X32677D01*
G01X32384Y1610335D02*
X32677Y1610089D01*
G01X32342D02*
X32283Y1610138D01*
G01D02*
X32049Y1610335D01*
G01X30315Y1611988D02*
X28740Y1613878D01*
G01X30315Y1611988D02*
X30709Y1611516D01*
G01X30315Y1622224D02*
X28740Y1625059D01*
G01X30315Y1622224D02*
X30709Y1621516D01*
G01X14055Y1608957D02*
X11220Y1615471D01*
G01X32677Y1620925D02*
Y1628957D01*
G01Y1610925D02*
Y1618957D01*
G01Y1606752D02*
Y1608957D01*
G01Y1610089D02*
Y1609843D01*
G01X32283Y1610925D02*
Y1608957D01*
G01Y1620925D02*
Y1618957D01*
G01X31535Y1610925D02*
Y1608957D01*
G01Y1620925D02*
Y1618957D01*
G01X30709Y1609843D02*
Y1610089D01*
G01X30315Y1617657D02*
Y1622224D01*
G01Y1618957D02*
Y1620925D01*
G01Y1608366D02*
Y1611988D01*
G01Y1610925D02*
Y1608957D01*
G01X28740Y1608366D02*
Y1631516D01*
G01X27559Y1626953D02*
Y1613773D01*
G01X17520Y1616634D02*
Y1611516D01*
G01X17289Y1628366D02*
Y1625020D01*
G01X11417Y1617224D02*
Y1615018D01*
G01Y1620925D02*
Y1618957D01*
G01X11220Y1627971D02*
Y1613773D01*
G01Y1627421D02*
Y1613839D01*
G01X9843Y1630374D02*
Y1609508D01*
G01X7283Y1627421D02*
Y1613839D01*
G01X6496Y1626831D02*
Y1613839D01*
G01X5906Y1606752D02*
Y1633130D01*
G01X0Y1626043D02*
Y1741535D01*
G01Y1613839D02*
Y1626043D01*
G01Y1613839D02*
Y1626043D01*
G01X-2953Y1613839D02*
Y1626043D01*
G01X-5906Y1625272D02*
Y1614610D01*
G01X28740Y1614823D02*
X30315Y1617657D01*
G01X30709Y1618366D02*
X30315Y1617657D01*
G01X11220Y1624232D02*
X14134Y1630925D01*
G01X28740Y1626398D02*
X30315Y1627972D01*
G01X16501Y1625020D02*
X13189Y1622657D01*
G01X0Y1626043D02*
Y1741535D01*
G01Y1626043D02*
Y1741535D01*
G01Y1613839D02*
Y1626043D01*
G01Y1613839D02*
Y1626043D01*
G01Y1613839D02*
Y1626043D01*
G01Y1613839D02*
Y1626043D01*
G01X17879Y1628957D02*
G03X17289Y1628366I1J-591D01*
G01X5906Y1633130D02*
X32677D01*
G01X28740Y1631516D02*
X30315D01*
G01X32677D02*
X30315D01*
G01X5906Y1631122D02*
X30315D01*
G01Y1630925D02*
X32283D01*
G01X30315D02*
X14134D01*
G01X32677D02*
X32283D01*
G01D02*
X30315D01*
G01Y1630374D02*
X9843D01*
G01X30315Y1628957D02*
X32283D01*
G01X17879D02*
X30315D01*
G01X32677D02*
X32283D01*
G01D02*
X30315D01*
G01X32677Y1628366D02*
X30709D01*
G01X11220Y1627971D02*
X5906D01*
G01X7283Y1627421D02*
X11220D01*
G01X27559Y1626953D02*
X11220D01*
G01X6496Y1626831D02*
X7283D01*
G01X32677Y1630925D02*
Y1633130D01*
G01X32283Y1630925D02*
Y1628957D01*
G01X31535Y1630925D02*
Y1628957D01*
G01X30315Y1627972D02*
Y1631516D01*
G01Y1630925D02*
Y1628957D01*
G01X30709Y1628366D02*
X30315Y1627972D01*
G01X0Y1659055D02*
G03X-7874I-3937J0D01*
G01X0D02*
G03X-7874I-3937J0D01*
G01Y1689764D02*
G03X0I3937J0D01*
G01X-7874D02*
G03X0I3937J0D01*
G01X17879Y1756654D02*
G03X17289Y1756063I1J-591D01*
G01X17520Y1739213D02*
G03X18110Y1738622I590J-1D01*
G01X17520Y1744331D02*
G03X16929Y1744921I-591J-1D01*
G01X11417Y1750354D02*
G03X11220Y1750157I0J-197D01*
G01Y1748819D02*
G03X11417Y1748622I197J0D01*
G01Y1746654D02*
G03X11220Y1746457I0J-197D01*
G01Y1745118D02*
G03X11417Y1744921I197J0D01*
G01X-2953Y1753740D02*
G03Y1741535I0J-6103D01*
G01X5906Y1760827D02*
X32677D01*
G01X28740Y1759213D02*
X30315D01*
G01X32677D02*
X30315D01*
G01X5906Y1758819D02*
X30315D01*
G01Y1758622D02*
X32283D01*
G01X30315D02*
X14134D01*
G01X32677D02*
X32283D01*
G01D02*
X30315D01*
G01Y1758071D02*
X9843D01*
G01X30315Y1756654D02*
X32283D01*
G01X17879D02*
X30315D01*
G01X32677D02*
X32283D01*
G01D02*
X30315D01*
G01X32677Y1756063D02*
X30709D01*
G01X11220Y1755668D02*
X5906D01*
G01X7283Y1755118D02*
X11220D01*
G01X27559Y1754650D02*
X11220D01*
G01X6496Y1754528D02*
X7283D01*
G01X5906Y1753740D02*
X-2953D01*
G01X6496D02*
X5906D01*
G01X17289Y1752717D02*
X16501D01*
G01X13189Y1750354D02*
X11417D01*
G01X32677Y1749213D02*
X30709D01*
G01X30315Y1748622D02*
X32283D01*
G01X11417D02*
X30315D01*
G01X32677D02*
X32283D01*
G01D02*
X30315D01*
G01Y1746654D02*
X11417D01*
G01X32283D02*
X30315D01*
G01X32677D02*
X32283D01*
G01D02*
X30315D01*
G01X32677Y1746063D02*
X30709D01*
G01X11417Y1744921D02*
X16929D01*
G01X5906Y1741535D02*
X11220D01*
G01X5906D02*
X-2953D01*
G01X11220Y1741496D02*
X5906D01*
G01X27559Y1741470D02*
X11220D01*
G01X32677Y1739213D02*
X30709D01*
G01X30315Y1738622D02*
X32283D01*
G01X18110D02*
X30315D01*
G01X32677D02*
X32283D01*
G01D02*
X30315D01*
G01X32283Y1738032D02*
X32384D01*
G01X32049D02*
X32283D01*
G01Y1737785D02*
X32342D01*
G01X30709D02*
X32283D01*
G01X32677Y1737539D02*
X32283D01*
G01D02*
X30709D01*
G01X30315Y1737205D02*
X9843D01*
G01X30315Y1736654D02*
X14055D01*
G01X32283D02*
X30315D01*
G01X32677D02*
X32283D01*
G01D02*
X30315D01*
G01X5906Y1736457D02*
X30315D01*
G01X28740Y1736063D02*
X30315D01*
G01X32677D02*
X30315D01*
G01X5906Y1734449D02*
X32677D01*
G01X32384Y1738032D02*
X32677Y1737785D01*
G01X32342D02*
X32283Y1737835D01*
G01D02*
X32049Y1738032D01*
G01X30315Y1739685D02*
X28740Y1741575D01*
G01X30315Y1739685D02*
X30709Y1739213D01*
G01X30315Y1749921D02*
X28740Y1752756D01*
G01X30315Y1749921D02*
X30709Y1749213D01*
G01X14055Y1736654D02*
X11220Y1743167D01*
G01X32677Y1758622D02*
Y1760827D01*
G01Y1748622D02*
Y1756654D01*
G01Y1738622D02*
Y1746654D01*
G01Y1734449D02*
Y1736654D01*
G01Y1737785D02*
Y1737539D01*
G01X32283Y1738622D02*
Y1736654D01*
G01Y1748622D02*
Y1746654D01*
G01Y1758622D02*
Y1756654D01*
G01X31535Y1738622D02*
Y1736654D01*
G01Y1748622D02*
Y1746654D01*
G01Y1758622D02*
Y1756654D01*
G01X30709Y1737539D02*
Y1737785D01*
G01X30315Y1755669D02*
Y1759213D01*
G01Y1745354D02*
Y1749921D01*
G01Y1746654D02*
Y1748622D01*
G01Y1736063D02*
Y1739685D01*
G01Y1738622D02*
Y1736654D01*
G01Y1758622D02*
Y1756654D01*
G01X28740Y1736063D02*
Y1759213D01*
G01X27559Y1754650D02*
Y1741470D01*
G01X17520Y1744331D02*
Y1739213D01*
G01X17289Y1756063D02*
Y1752717D01*
G01X11417Y1744921D02*
Y1742715D01*
G01Y1748622D02*
Y1746654D01*
G01X11220Y1755118D02*
Y1741535D01*
G01Y1755668D02*
Y1741470D01*
G01X9843Y1758071D02*
Y1737205D01*
G01X7283Y1755118D02*
Y1741535D01*
G01X6496Y1754528D02*
Y1741535D01*
G01X5906Y1734449D02*
Y1760827D01*
G01X0Y1753740D02*
Y1875394D01*
G01Y1741535D02*
Y1753740D01*
G01Y1741535D02*
Y1753740D01*
G01X-2953Y1741535D02*
Y1753740D01*
G01X-5906Y1752968D02*
Y1742307D01*
G01X11220Y1751929D02*
X14134Y1758622D01*
G01X28740Y1742520D02*
X30315Y1745354D01*
G01X30709Y1746063D02*
X30315Y1745354D01*
G01X28740Y1754094D02*
X30315Y1755669D01*
G01X30709Y1756063D02*
X30315Y1755669D01*
G01X16501Y1752717D02*
X13189Y1750354D01*
G01X0Y1753740D02*
Y1875394D01*
G01Y1753740D02*
Y1875394D01*
G01Y1741535D02*
Y1753740D01*
G01Y1741535D02*
Y1753740D01*
G01Y1741535D02*
Y1753740D01*
G01Y1741535D02*
Y1753740D01*
G01X34449Y1811024D02*
G03I-6890J0D01*
G01X13907Y1881654D02*
G03Y1879134I1998J-1260D01*
G01X37008Y1857087D02*
G03I-7087J0D01*
G01X10000Y1881654D02*
X8819D01*
G01X17165D02*
X10000D01*
G01X16575Y1881063D02*
X15236D01*
G01Y1879724D02*
X16575D01*
G01X10000Y1879134D02*
X8819D01*
G01X17165D02*
X10000D01*
G01X0Y1876969D02*
X10000D01*
G01X0Y1876181D02*
X10000D01*
G01X0Y1875394D02*
X10000D01*
G01X17165Y1879134D02*
X16575Y1879724D01*
G01X15236Y1881063D02*
X14646Y1881654D01*
G01X17165D02*
Y1879134D01*
G01X16575Y1879724D02*
Y1881063D01*
G01X15236Y1879724D02*
Y1881063D01*
G01X14646Y1881654D02*
Y1879134D01*
G01X13661Y1881654D02*
Y1879134D01*
G01X10000Y1875394D02*
Y1925394D01*
G01X8819D02*
Y1875394D01*
G01X0D02*
Y1925394D01*
G01Y1875394D02*
Y1925394D01*
G01Y1875394D02*
Y1925394D01*
G01X16575Y1881063D02*
X17165Y1881654D01*
G01X15236Y1879724D02*
X14646Y1879134D01*
G01X0Y1875394D02*
Y1925394D01*
G01Y1875394D02*
Y1925394D01*
G01Y1875394D02*
Y1925394D01*
G01X13907Y1891654D02*
G03Y1889134I1998J-1260D01*
G01Y1901654D02*
G03Y1899134I1998J-1260D01*
G01Y1911654D02*
G03Y1909134I1998J-1260D01*
G01Y1921654D02*
G03Y1919134I1998J-1260D01*
G01X0Y1925394D02*
X10000D01*
G01Y1924606D02*
X0D01*
G01X10000Y1923819D02*
X0D01*
G01X10000Y1921654D02*
X8819D01*
G01X17165D02*
X10000D01*
G01X18543Y1921432D02*
X20512D01*
G01Y1921186D02*
X18878D01*
G01X16575Y1921063D02*
X15236D01*
G01X19172Y1920940D02*
X18836D01*
G01X19004Y1920612D02*
X19172D01*
G01X19130Y1920366D02*
X19004D01*
G01X15236Y1919724D02*
X16575D01*
G01X18753Y1919341D02*
X19381D01*
G01X19632D02*
X20512D01*
G01X10000Y1919134D02*
X8819D01*
G01X17165D02*
X10000D01*
G01X20512Y1919094D02*
X18543D01*
G01X0Y1916969D02*
X10000D01*
G01X0Y1916181D02*
X10000D01*
G01Y1914606D02*
X0D01*
G01X10000Y1913819D02*
X0D01*
G01X10000Y1911654D02*
X8819D01*
G01X17165D02*
X10000D01*
G01X16575Y1911063D02*
X15236D01*
G01Y1909724D02*
X16575D01*
G01X10000Y1909134D02*
X8819D01*
G01X17165D02*
X10000D01*
G01X0Y1906969D02*
X10000D01*
G01X0Y1906181D02*
X10000D01*
G01Y1904606D02*
X0D01*
G01X10000Y1903819D02*
X0D01*
G01X10000Y1901654D02*
X8819D01*
G01X17165D02*
X10000D01*
G01X16575Y1901063D02*
X15236D01*
G01Y1899724D02*
X16575D01*
G01X10000Y1899134D02*
X8819D01*
G01X17165D02*
X10000D01*
G01X0Y1896969D02*
X10000D01*
G01X0Y1896181D02*
X10000D01*
G01Y1894606D02*
X0D01*
G01X10000Y1893819D02*
X0D01*
G01X10000Y1891654D02*
X8819D01*
G01X17165D02*
X10000D01*
G01X16575Y1891063D02*
X15236D01*
G01Y1889724D02*
X16575D01*
G01X10000Y1889134D02*
X8819D01*
G01X17165D02*
X10000D01*
G01X0Y1886969D02*
X10000D01*
G01X0Y1886181D02*
X10000D01*
G01Y1884606D02*
X0D01*
G01X10000Y1883819D02*
X0D01*
G01X19172Y1920612D02*
X19297Y1920571D01*
G01X19255Y1920325D02*
X19130Y1920366D01*
G01X18878Y1921186D02*
X19172Y1920940D01*
G01X18836D02*
X18543Y1921186D01*
G01X19297Y1920571D02*
X19465Y1920448D01*
G01X15236Y1921063D02*
X14646Y1921654D01*
G01X17165Y1919134D02*
X16575Y1919724D01*
G01X19339Y1920243D02*
X19255Y1920325D01*
G01X15236Y1911063D02*
X14646Y1911654D01*
G01X17165Y1909134D02*
X16575Y1909724D01*
G01X15236Y1901063D02*
X14646Y1901654D01*
G01X17165Y1899134D02*
X16575Y1899724D01*
G01X15236Y1891063D02*
X14646Y1891654D01*
G01X17165Y1889134D02*
X16575Y1889724D01*
G01X19465Y1920448D02*
X19590Y1920284D01*
G01X19381Y1920120D02*
X19339Y1920243D01*
G01X19590Y1920284D02*
X19632Y1920079D01*
G01X20512Y1921432D02*
Y1921186D01*
G01Y1919341D02*
Y1919094D01*
G01X19632Y1920079D02*
Y1919341D01*
G01X19381D02*
Y1920120D01*
G01X18753D02*
Y1919341D01*
G01X18543Y1921186D02*
Y1921432D01*
G01Y1919094D02*
Y1920079D01*
G01X17165Y1891654D02*
Y1889134D01*
G01Y1901654D02*
Y1899134D01*
G01Y1911654D02*
Y1909134D01*
G01Y1921654D02*
Y1919134D01*
G01X16575Y1919724D02*
Y1921063D01*
G01Y1909724D02*
Y1911063D01*
G01Y1899724D02*
Y1901063D01*
G01Y1889724D02*
Y1891063D01*
G01X15236Y1919724D02*
Y1921063D01*
G01Y1909724D02*
Y1911063D01*
G01Y1899724D02*
Y1901063D01*
G01Y1889724D02*
Y1891063D01*
G01X14646Y1891654D02*
Y1889134D01*
G01Y1901654D02*
Y1899134D01*
G01Y1911654D02*
Y1909134D01*
G01Y1921654D02*
Y1919134D01*
G01X13661Y1891654D02*
Y1889134D01*
G01Y1901654D02*
Y1899134D01*
G01Y1911654D02*
Y1909134D01*
G01Y1921654D02*
Y1919134D01*
G01X0Y1925394D02*
Y1964567D01*
G01X18543Y1920079D02*
X18585Y1920284D01*
G01X18795Y1920243D02*
X18753Y1920120D01*
G01X18585Y1920284D02*
X18711Y1920448D01*
G01X16575Y1891063D02*
X17165Y1891654D01*
G01X15236Y1889724D02*
X14646Y1889134D01*
G01X16575Y1901063D02*
X17165Y1901654D01*
G01X15236Y1899724D02*
X14646Y1899134D01*
G01X16575Y1911063D02*
X17165Y1911654D01*
G01X15236Y1909724D02*
X14646Y1909134D01*
G01X16575Y1921063D02*
X17165Y1921654D01*
G01X15236Y1919724D02*
X14646Y1919134D01*
G01X18878Y1920325D02*
X18795Y1920243D01*
G01X18711Y1920448D02*
X18878Y1920571D01*
G01X19004Y1920366D02*
X18878Y1920325D01*
G01Y1920571D02*
X19004Y1920612D01*
G01X0Y1925394D02*
Y1964567D01*
G01Y1925394D02*
Y1964567D01*
G01Y1925984D02*
G03X-7874I-3937J0D01*
G01X0D02*
G03X-7874I-3937J0D01*
G01X37008Y1943701D02*
G03I-7087J0D01*
G01X3937Y1968504D02*
G03X0Y1964567I0J-3937D01*
G01X3937Y1968504D02*
X64961D01*
G01X-7874Y1964813D02*
Y2005727D01*
G01X0Y1980315D02*
X5730Y1991584D01*
G01X0Y1964813D02*
Y1980315D01*
G01X3937Y1968504D02*
G03X0Y1964567I0J-3937D01*
G01X3937Y1968504D02*
G03X0Y1964567I0J-3937D01*
G01X3937Y1968504D02*
X64961D01*
G01X3937D02*
X64961D01*
G01X-7874Y1956693D02*
G03X0I3937J0D01*
G01X-7874D02*
G03X0I3937J0D01*
G01X-7874Y1964567D02*
G03X-11811Y1968504I-3937J0D01*
G01X-7874Y1964567D02*
G03X-11811Y1968504I-3937J0D01*
G01X3937D02*
G03X0Y1964567I0J-3937D01*
G01X3937Y1968504D02*
G03X0Y1964567I0J-3937D01*
G01X3937Y1968504D02*
X64961D01*
G01X3937D02*
X64961D01*
G01X3937D02*
G03X0Y1964567I0J-3937D01*
G01X64961Y1968504D02*
X3937D01*
G01X-7874Y1964567D02*
G03X-11811Y1968504I-3937J0D01*
G01X3937D02*
G03X0Y1964567I0J-3937D01*
G01X64961Y1968504D02*
X3937D01*
G01X-7874Y1964567D02*
G03X-11811Y1968504I-3937J0D01*
G01X6511Y2008727D02*
X5627Y2009390D01*
X5122Y2009958D01*
X4870Y2010716D01*
X5122Y2011379D01*
X5627Y2011852D01*
X6385Y2012231D01*
X7268Y2012326D01*
X8026Y2012231D01*
X8783Y2011852D01*
X9415Y2011284D01*
X9667Y2010621D01*
X9415Y2009864D01*
X8657Y2009201D01*
X7521Y2008822D01*
X6258Y2008727D01*
X4617Y2008917D01*
X3733Y2009201D01*
X2850Y2009674D01*
X2218Y2010337D01*
X2092Y2011000D01*
X2344Y2011663D01*
X2976Y2012136D01*
G01X9667Y2018101D02*
X2092D01*
X3607Y2016965D01*
G01X9667D02*
Y2019238D01*
G01X9919Y2025676D02*
X9793Y2025487D01*
X9541D01*
X9415Y2025676D01*
X9541Y2025866D01*
X9793D01*
X9919Y2025676D01*
G01X8531Y2031168D02*
X9162Y2031736D01*
X9541Y2032399D01*
X9667Y2033251D01*
X9415Y2034104D01*
X8910Y2034766D01*
X8026Y2035240D01*
X7016Y2035335D01*
X6006Y2035145D01*
X5374Y2034672D01*
X4870Y2034009D01*
X4743Y2033346D01*
X4870Y2032683D01*
X5374Y2031831D01*
X2092Y2032115D01*
Y2034672D01*
G01Y2040826D02*
X2344Y2040069D01*
X2976Y2039501D01*
X3733Y2039122D01*
X4743Y2038838D01*
X5880Y2038743D01*
X7016Y2038838D01*
X8026Y2039122D01*
X8783Y2039501D01*
X9415Y2040069D01*
X9667Y2040826D01*
X9415Y2041584D01*
X8783Y2042152D01*
X8026Y2042531D01*
X7016Y2042815D01*
X5880Y2042910D01*
X4743Y2042815D01*
X3733Y2042531D01*
X2976Y2042152D01*
X2344Y2041584D01*
X2092Y2040826D01*
G01X-5073Y2006838D02*
X-4442Y2007406D01*
X-4063Y2008069D01*
X-3937Y2008921D01*
X-4189Y2009774D01*
X-4694Y2010436D01*
X-5578Y2010910D01*
X-6588Y2011005D01*
X-7598Y2010815D01*
X-8230Y2010342D01*
X-8734Y2009679D01*
X-8861Y2009016D01*
X-8734Y2008353D01*
X-8230Y2007501D01*
X-11512Y2007785D01*
Y2010342D01*
G01X-4821Y2014887D02*
X-4189Y2015550D01*
X-3937Y2016307D01*
X-4189Y2017065D01*
X-4947Y2017727D01*
X-6083Y2018201D01*
X-7219Y2018390D01*
X-8608D01*
X-9744Y2018201D01*
X-10754Y2017727D01*
X-11260Y2017159D01*
X-11512Y2016496D01*
X-11260Y2015739D01*
X-10754Y2015171D01*
X-9997Y2014792D01*
X-8987Y2014603D01*
X-8103Y2014792D01*
X-7219Y2015266D01*
X-6714Y2015834D01*
X-6588Y2016496D01*
X-6841Y2017254D01*
X-7472Y2017822D01*
X-8608Y2018390D01*
G01X-3685Y2024071D02*
X-3811Y2023882D01*
X-4063D01*
X-4189Y2024071D01*
X-4063Y2024261D01*
X-3811D01*
X-3685Y2024071D01*
G01X-5073Y2029563D02*
X-4442Y2030131D01*
X-4063Y2030794D01*
X-3937Y2031646D01*
X-4189Y2032499D01*
X-4694Y2033161D01*
X-5578Y2033635D01*
X-6588Y2033730D01*
X-7598Y2033540D01*
X-8230Y2033067D01*
X-8734Y2032404D01*
X-8861Y2031741D01*
X-8734Y2031078D01*
X-8230Y2030226D01*
X-11512Y2030510D01*
Y2033067D01*
G01Y2039221D02*
X-11260Y2038464D01*
X-10628Y2037896D01*
X-9871Y2037517D01*
X-8861Y2037233D01*
X-7724Y2037138D01*
X-6588Y2037233D01*
X-5578Y2037517D01*
X-4821Y2037896D01*
X-4189Y2038464D01*
X-3937Y2039221D01*
X-4189Y2039979D01*
X-4821Y2040547D01*
X-5578Y2040926D01*
X-6588Y2041210D01*
X-7724Y2041305D01*
X-8861Y2041210D01*
X-9871Y2040926D01*
X-10628Y2040547D01*
X-11260Y2039979D01*
X-11512Y2039221D01*
G01X5730Y1991584D02*
Y2007332D01*
G01X18947Y2099793D02*
X19799Y2098468D01*
X20936Y2097710D01*
X22214Y2097521D01*
X23350Y2097710D01*
X24487Y2098657D01*
X25197Y2099793D01*
X25339Y2100930D01*
X25055Y2102255D01*
X24060Y2103202D01*
X23066Y2103581D01*
X21788D01*
G01X23066D02*
X23918Y2104149D01*
X24629Y2105095D01*
X24913Y2106232D01*
X24629Y2107368D01*
X23918Y2108315D01*
X22640Y2108883D01*
X21362Y2108694D01*
X20084Y2107936D01*
G01X72835Y39370D02*
G03X68898Y35433I0J-3937D01*
G01X64961Y0D02*
G03X68898Y3937I0J3937D01*
G01Y35433D02*
Y3937D01*
G01X202756Y39370D02*
X72835D01*
G01D02*
G03X68898Y35433I0J-3937D01*
G01X72835Y39370D02*
G03X68898Y35433I0J-3937D01*
G01X64961Y0D02*
G03X68898Y3937I0J3937D01*
G01X64961Y0D02*
G03X68898Y3937I0J3937D01*
G01Y35433D02*
Y3937D01*
G01Y35433D02*
Y3937D01*
G01X202756Y39370D02*
X72835D01*
G01X202756D02*
X72835D01*
G01X168110Y31496D02*
X76763D01*
G01X72835Y39370D02*
G03X68898Y35433I0J-3937D01*
G01X72835Y39370D02*
G03X68898Y35433I0J-3937D01*
G01X64961Y0D02*
G03X68898Y3937I0J3937D01*
G01X64961Y0D02*
G03X68898Y3937I0J3937D01*
G01Y35433D02*
Y3937D01*
G01Y35433D02*
Y3937D01*
G01X202756Y39370D02*
X72835D01*
G01X202756D02*
X72835D01*
G01D02*
X202756D01*
G01X72835D02*
G03X68898Y35433I0J-3937D01*
G01Y3937D02*
Y35485D01*
G01X64961Y0D02*
G03X68898Y3937I0J3937D01*
G01X76763D02*
G03X80700Y0I3937J0D01*
G01X76763Y7615D02*
Y3937D01*
G01X80700Y0D02*
X340551D01*
G01X76763Y3937D02*
Y7615D01*
G01X168110Y31496D02*
X76763D01*
G01Y7615D02*
G03X68889I-3937J0D01*
G01Y31496D02*
G03X76763I3937J0D01*
G01X72835Y39370D02*
X202756D01*
G01X72835D02*
G03X68898Y35433I0J-3937D01*
G01Y3937D02*
Y35485D01*
G01X64961Y0D02*
G03X68898Y3937I0J3937D01*
G01X76763D02*
G03X80700Y0I3937J0D01*
G01X76763Y7615D02*
Y3937D01*
G01X80700Y0D02*
X340551D01*
G01X76763Y3937D02*
Y7615D01*
G01X168110Y31496D02*
X76763D01*
G01Y7615D02*
G03X68889I-3937J0D01*
G01Y31496D02*
G03X76763I3937J0D01*
G01X52953Y68110D02*
G03I-5709J0D01*
G01X85610Y139409D02*
G03I-4901J0D01*
G01X86809Y119409D02*
G03I-6100J0D01*
G01X86969D02*
G03I-6260J0D01*
G01X82059Y144359D02*
Y134459D01*
G01X79359D02*
Y144359D01*
G01X67009Y109409D02*
Y339409D01*
G01Y139409D02*
X94409D01*
G01X82059Y134459D02*
X79359D01*
G01X67009Y109409D02*
X94409D01*
G01X78979Y162910D02*
G03X82438I1730J-1020D01*
G01X78979Y182910D02*
G03X82438I1730J-1020D01*
G01X82461Y170909D02*
G03X78956I-1753J980D01*
G01X82461Y190909D02*
G03X78956I-1753J980D01*
G01X83346Y162909D02*
Y160909D01*
G01Y172909D02*
Y170909D01*
G01Y182909D02*
Y180909D01*
G01Y192909D02*
Y190909D01*
G01X81959D02*
Y192909D01*
G01Y180909D02*
Y182909D01*
G01Y170909D02*
Y172909D01*
G01Y160909D02*
Y162909D01*
G01X79459D02*
Y160909D01*
G01Y172909D02*
Y170909D01*
G01Y182909D02*
Y180909D01*
G01Y192909D02*
Y190909D01*
G01X78553D02*
Y192909D01*
G01Y180909D02*
Y182909D01*
G01Y170909D02*
Y172909D01*
G01Y160909D02*
Y162909D01*
G01X77939Y182909D02*
Y190909D01*
G01Y162909D02*
Y170909D01*
G01X72009Y154409D02*
Y199409D01*
G01X70009Y143409D02*
Y305409D01*
G01X78553Y192909D02*
X109414D01*
G01X77939Y190909D02*
X113339D01*
G01X77939Y182909D02*
X113339D01*
G01X78553Y180909D02*
X109414D01*
G01X78553Y172909D02*
X109414D01*
G01X77939Y170909D02*
X113339D01*
G01X77939Y162909D02*
X113339D01*
G01X78553Y160909D02*
X109414D01*
G01X70009Y154409D02*
X121409D01*
G01X79359Y144359D02*
X82059D01*
G01X86509Y143409D02*
X70009D01*
G01X82717Y224409D02*
G03I-2008J0D01*
G01Y234409D02*
G03I-2008J0D01*
G01Y244409D02*
G03I-2008J0D01*
G01Y204409D02*
G03I-2008J0D01*
G01Y214409D02*
G03I-2008J0D01*
G01X79068Y202769D02*
X79459Y203159D01*
G01X82349Y206050D02*
X81959Y205659D01*
G01X79068Y212769D02*
X79459Y213159D01*
G01X82349Y216050D02*
X81959Y215659D01*
G01X79068Y222769D02*
X79459Y223159D01*
G01X82349Y226050D02*
X81959Y225659D01*
G01X79068Y232769D02*
X79459Y233159D01*
G01X82349Y236050D02*
X81959Y235659D01*
G01X79068Y242769D02*
X79459Y243159D01*
G01X82349Y206050D02*
Y202769D01*
G01Y216050D02*
Y212769D01*
G01Y226050D02*
Y222769D01*
G01Y236050D02*
Y232769D01*
G01Y246050D02*
Y242769D01*
G01X82089Y205789D02*
Y203029D01*
G01Y215789D02*
Y213029D01*
G01Y225789D02*
Y223029D01*
G01Y235789D02*
Y233029D01*
G01Y245789D02*
Y243029D01*
G01X81959Y205659D02*
Y203159D01*
G01Y215659D02*
Y213159D01*
G01Y225659D02*
Y223159D01*
G01Y235659D02*
Y233159D01*
G01Y245659D02*
Y243159D01*
G01X79459D02*
Y245659D01*
G01Y233159D02*
Y235659D01*
G01Y223159D02*
Y225659D01*
G01Y213159D02*
Y215659D01*
G01Y203159D02*
Y205659D01*
G01X79329Y243029D02*
Y245789D01*
G01Y233029D02*
Y235789D01*
G01Y223029D02*
Y225789D01*
G01Y213029D02*
Y215789D01*
G01Y203029D02*
Y205789D01*
G01X79068Y242769D02*
Y246050D01*
G01Y232769D02*
Y236050D01*
G01Y222769D02*
Y226050D01*
G01Y212769D02*
Y216050D01*
G01Y202769D02*
Y206050D01*
G01X72209Y199409D02*
Y249409D01*
G01X81959Y243159D02*
X82349Y242769D01*
G01X81959Y233159D02*
X82349Y232769D01*
G01X79068Y236050D02*
X79459Y235659D01*
G01X81959Y223159D02*
X82349Y222769D01*
G01X79068Y226050D02*
X79459Y225659D01*
G01X81959Y213159D02*
X82349Y212769D01*
G01X79068Y216050D02*
X79459Y215659D01*
G01X81959Y203159D02*
X82349Y202769D01*
G01X79068Y206050D02*
X79459Y205659D01*
G01X81959Y243159D02*
X79459D01*
G01X82089Y243029D02*
X79329D01*
G01X82349Y242769D02*
X79068D01*
G01Y236050D02*
X82349D01*
G01X79329Y235789D02*
X82089D01*
G01X79459Y235659D02*
X81959D01*
G01Y233159D02*
X79459D01*
G01X82089Y233029D02*
X79329D01*
G01X82349Y232769D02*
X79068D01*
G01Y226050D02*
X82349D01*
G01X79329Y225789D02*
X82089D01*
G01X79459Y225659D02*
X81959D01*
G01Y223159D02*
X79459D01*
G01X82089Y223029D02*
X79329D01*
G01X82349Y222769D02*
X79068D01*
G01Y216050D02*
X82349D01*
G01X79329Y215789D02*
X82089D01*
G01X79459Y215659D02*
X81959D01*
G01Y213159D02*
X79459D01*
G01X82089Y213029D02*
X79329D01*
G01X82349Y212769D02*
X79068D01*
G01Y206050D02*
X82349D01*
G01X79329Y205789D02*
X82089D01*
G01X79459Y205659D02*
X81959D01*
G01Y203159D02*
X79459D01*
G01X82089Y203029D02*
X79329D01*
G01X82349Y202769D02*
X79068D01*
G01X70013Y199409D02*
X72209D01*
G01X78956Y277910D02*
G03X82461I1753J-981D01*
G01X82438Y285909D02*
G03X78979I-1729J1020D01*
G01X78956Y257910D02*
G03X82461I1753J-981D01*
G01X82438Y265909D02*
G03X78979I-1729J1020D01*
G01X83846Y286756D02*
X83771Y286731D01*
G01Y286879D02*
X83846Y286904D01*
G01X83947Y286830D02*
X83846Y286756D01*
G01Y286904D02*
X83896Y286953D01*
G01X82349Y246050D02*
X81959Y245659D01*
G01X84022Y286928D02*
X83947Y286830D01*
G01X83896Y286953D02*
X83922Y287027D01*
G01X84047Y287051D02*
X84022Y286928D01*
G01X84047Y286387D02*
Y286239D01*
G01Y287642D02*
Y287051D01*
G01X83922Y287027D02*
Y287494D01*
G01X83545D02*
Y287027D01*
G01X83394Y287051D02*
Y287494D01*
G01X83346Y257909D02*
Y255909D01*
G01Y267909D02*
Y265909D01*
G01Y277909D02*
Y275909D01*
G01Y287909D02*
Y285909D01*
G01X82866Y287494D02*
Y287642D01*
G01Y286239D02*
Y286387D01*
G01X81959Y285909D02*
Y287909D01*
G01Y275909D02*
Y277909D01*
G01Y265909D02*
Y267909D01*
G01Y255909D02*
Y257909D01*
G01X79459D02*
Y255909D01*
G01Y267909D02*
Y265909D01*
G01Y277909D02*
Y275909D01*
G01Y287909D02*
Y285909D01*
G01X78553D02*
Y287909D01*
G01Y275909D02*
Y277909D01*
G01Y265909D02*
Y267909D01*
G01Y255909D02*
Y257909D01*
G01X77939Y277909D02*
Y285909D01*
G01Y257909D02*
Y265909D01*
G01X72009Y249409D02*
Y294409D01*
G01X83419Y286928D02*
X83394Y287051D01*
G01X83545Y287027D02*
X83570Y286953D01*
G01X83494Y286830D02*
X83419Y286928D01*
G01X83570Y286953D02*
X83620Y286904D01*
G01X79068Y246050D02*
X79459Y245659D01*
G01X83871Y286534D02*
X84047Y286387D01*
G01X83846D02*
X83670Y286534D01*
G01X83595Y286756D02*
X83494Y286830D01*
G01X83620Y286904D02*
X83695Y286879D01*
G01X83670Y286731D02*
X83595Y286756D01*
G01X70009Y294409D02*
X121409D01*
G01X78553Y287909D02*
X109414D01*
G01X82866Y287642D02*
X84047D01*
G01X83922Y287494D02*
X83545D01*
G01X83394D02*
X82866D01*
G01X83695Y286879D02*
X83771D01*
G01Y286731D02*
X83670D01*
G01Y286534D02*
X83871D01*
G01X82866Y286387D02*
X83846D01*
G01X84047Y286239D02*
X82866D01*
G01X77939Y285909D02*
X113339D01*
G01X77939Y277909D02*
X113339D01*
G01X78553Y275909D02*
X109414D01*
G01X78553Y267909D02*
X109414D01*
G01X77939Y265909D02*
X113339D01*
G01X77939Y257909D02*
X113339D01*
G01X78553Y255909D02*
X109414D01*
G01X70013Y249409D02*
X72209D01*
G01X79068Y246050D02*
X82349D01*
G01X79329Y245789D02*
X82089D01*
G01X79459Y245659D02*
X81959D01*
G01X85610Y309409D02*
G03I-4901J0D01*
G01X86809Y329409D02*
G03I-6100J0D01*
G01X86969D02*
G03I-6260J0D01*
G01X82059Y314359D02*
Y304459D01*
G01X79359D02*
Y314359D01*
G01X94409Y339409D02*
X67009D01*
G01X79359Y314359D02*
X82059D01*
G01X94409Y309409D02*
X67009D01*
G01X70009Y305409D02*
X86509D01*
G01X82059Y304459D02*
X79359D01*
G01X52953Y501339D02*
G03I-5709J0D01*
G01Y761181D02*
G03I-5709J0D01*
G01Y1207323D02*
G03I-5709J0D01*
G01Y1467165D02*
G03I-5709J0D01*
G01X123424Y1689960D02*
X69487D01*
G01X123424D02*
X69487D01*
G01D02*
Y1856889D01*
G01Y1689960D02*
Y1856889D01*
G01X115156Y1747834D02*
G03I-18701J0D01*
G01X111613D02*
G03I-15158J0D01*
G01X112203D02*
G03I-15748J0D01*
G01X111613Y1823031D02*
G03I-15158J0D01*
G01X112203D02*
G03I-15748J0D01*
G01X115156D02*
G03I-18701J0D01*
G01X69487Y1856889D02*
X123424D01*
G01X69487D02*
X123424D01*
G01X68898Y1933071D02*
G03X72835Y1929134I3937J0D01*
G01X52953Y1900394D02*
G03I-5709J0D01*
G01X72835Y1929134D02*
X202756D01*
G01X68898Y1964567D02*
Y1933071D01*
G01D02*
G03X72835Y1929134I3937J0D01*
G01X68898Y1933071D02*
G03X72835Y1929134I3937J0D01*
G01D02*
X202756D01*
G01X72835D02*
X202756D01*
G01X68898Y1964567D02*
Y1933071D01*
G01Y1964567D02*
Y1933071D01*
G01D02*
G03X72835Y1929134I3937J0D01*
G01X68898Y1933071D02*
G03X72835Y1929134I3937J0D01*
G01D02*
X202756D01*
G01X72835D02*
X202756D01*
G01X68898Y1964567D02*
Y1933071D01*
G01Y1964567D02*
Y1933071D01*
G01D02*
Y1964567D01*
G01Y1933071D02*
G03X72835Y1929134I3937J0D01*
G01X202756D02*
X72835D01*
G01X68898Y1933071D02*
Y1964567D01*
G01Y1933071D02*
G03X72835Y1929134I3937J0D01*
G01X202756D02*
X72835D01*
G01X68898Y1964567D02*
G03X64961Y1968504I-3937J0D01*
G01X68898Y1964567D02*
G03X64961Y1968504I-3937J0D01*
G01X68898Y1964567D02*
G03X64961Y1968504I-3937J0D01*
G01X68898Y1964567D02*
G03X64961Y1968504I-3937J0D01*
G01X68898Y1964567D02*
G03X64961Y1968504I-3937J0D01*
G01X68898Y1964567D02*
G03X64961Y1968504I-3937J0D01*
G01X109377D02*
X80709D01*
G01D02*
G03X76772Y1964567I0J-3937D01*
G01Y1960630D02*
Y1964567D01*
G01X168110Y1937008D02*
X76772D01*
G01X68898Y1960630D02*
G03X76772I3937J0D01*
G01Y1937008D02*
G03X68898I-3937J0D01*
G01Y1964567D02*
G03X64961Y1968504I-3937J0D01*
G01X109377D02*
X80709D01*
G01D02*
G03X76772Y1964567I0J-3937D01*
G01Y1960630D02*
Y1964567D01*
G01X168110Y1937008D02*
X76772D01*
G01X68898Y1960630D02*
G03X76772I3937J0D01*
G01Y1937008D02*
G03X68898I-3937J0D01*
G01X131433Y-65085D02*
Y-84022D01*
G01X135906Y109409D02*
Y339409D01*
G01X124409Y137909D02*
Y310909D01*
G01X94409Y109409D02*
Y145409D01*
G01X135906Y139409D02*
X163306D01*
G01X124409Y137909D02*
X94409D01*
G01X135906Y109409D02*
X163306D01*
G01X108979Y182910D02*
G03X112438I1730J-1020D01*
G01X112461Y190909D02*
G03X108956I-1752J980D01*
G01X108979Y162910D02*
G03X112438I1730J-1020D01*
G01X112461Y170909D02*
G03X108956I-1752J980D01*
G01X98979Y182910D02*
G03X102438I1730J-1020D01*
G01X102461Y190909D02*
G03X98956I-1753J980D01*
G01X98979Y162910D02*
G03X102438I1730J-1020D01*
G01X102461Y170909D02*
G03X98956I-1753J980D01*
G01X88979Y162910D02*
G03X92438I1730J-1020D01*
G01X88979Y182910D02*
G03X92438I1730J-1020D01*
G01X92461Y170909D02*
G03X88956I-1753J980D01*
G01X92461Y190909D02*
G03X88956I-1753J980D01*
G01X121409Y298409D02*
Y150409D01*
G01X119409Y154409D02*
Y199409D01*
G01X113339Y170909D02*
Y162909D01*
G01Y190909D02*
Y182909D01*
G01X111959Y190909D02*
Y192909D01*
G01Y180909D02*
Y182909D01*
G01Y170909D02*
Y172909D01*
G01Y160909D02*
Y162909D01*
G01X109459D02*
Y160909D01*
G01Y172909D02*
Y170909D01*
G01Y182909D02*
Y180909D01*
G01Y192909D02*
Y190909D01*
G01X109414Y162909D02*
Y160909D01*
G01Y172909D02*
Y170909D01*
G01Y182909D02*
Y180909D01*
G01Y192909D02*
Y190909D01*
G01X104622Y162909D02*
Y160909D01*
G01Y172909D02*
Y170909D01*
G01Y182909D02*
Y180909D01*
G01Y192909D02*
Y190909D01*
G01X101959D02*
Y192909D01*
G01Y180909D02*
Y182909D01*
G01Y170909D02*
Y172909D01*
G01Y160909D02*
Y162909D01*
G01X99459D02*
Y160909D01*
G01Y172909D02*
Y170909D01*
G01Y182909D02*
Y180909D01*
G01Y192909D02*
Y190909D01*
G01X94409Y145409D02*
Y145909D01*
G01X91959Y190909D02*
Y192909D01*
G01Y180909D02*
Y182909D01*
G01Y170909D02*
Y172909D01*
G01Y160909D02*
Y162909D01*
G01X89459D02*
Y160909D01*
G01Y172909D02*
Y170909D01*
G01Y182909D02*
Y180909D01*
G01Y192909D02*
Y190909D01*
G01X86509Y150409D02*
Y143409D01*
G01X111959Y192909D02*
X109459D01*
G01Y180909D02*
X111959D01*
G01Y172909D02*
X109459D01*
G01Y160909D02*
X111959D01*
G01X121409Y150409D02*
X86509D01*
G01X94409Y145909D02*
X124409D01*
G01X94409Y145409D02*
X124409D01*
G01X112717Y204409D02*
G03I-2008J0D01*
G01Y214409D02*
G03I-2008J0D01*
G01Y224409D02*
G03I-2008J0D01*
G01Y234409D02*
G03I-2008J0D01*
G01Y244409D02*
G03I-2008J0D01*
G01X102717Y204409D02*
G03I-2008J0D01*
G01Y214409D02*
G03I-2008J0D01*
G01Y224409D02*
G03I-2008J0D01*
G01Y234409D02*
G03I-2008J0D01*
G01Y244409D02*
G03I-2008J0D01*
G01X92717Y224409D02*
G03I-2008J0D01*
G01Y234409D02*
G03I-2008J0D01*
G01Y244409D02*
G03I-2008J0D01*
G01Y204409D02*
G03I-2008J0D01*
G01Y214409D02*
G03I-2008J0D01*
G01X111959Y205659D02*
X112349Y206050D01*
G01X109459Y203159D02*
X109068Y202769D01*
G01X111959Y215659D02*
X112349Y216050D01*
G01X99068Y202769D02*
X99459Y203159D01*
G01X102349Y206050D02*
X101959Y205659D01*
G01X109459Y213159D02*
X109068Y212769D01*
G01X111959Y225659D02*
X112349Y226050D01*
G01X99068Y212769D02*
X99459Y213159D01*
G01X89068Y202769D02*
X89459Y203159D01*
G01X92349Y206050D02*
X91959Y205659D01*
G01X102349Y216050D02*
X101959Y215659D01*
G01X109459Y223159D02*
X109068Y222769D01*
G01X111959Y235659D02*
X112349Y236050D01*
G01X99068Y222769D02*
X99459Y223159D01*
G01X89068Y212769D02*
X89459Y213159D01*
G01X92349Y216050D02*
X91959Y215659D01*
G01X102349Y226050D02*
X101959Y225659D01*
G01X109459Y233159D02*
X109068Y232769D01*
G01X99068D02*
X99459Y233159D01*
G01X89068Y222769D02*
X89459Y223159D01*
G01X92349Y226050D02*
X91959Y225659D01*
G01X102349Y236050D02*
X101959Y235659D01*
G01X109459Y243159D02*
X109068Y242769D01*
G01X99068D02*
X99459Y243159D01*
G01X89068Y232769D02*
X89459Y233159D01*
G01X92349Y236050D02*
X91959Y235659D01*
G01X89068Y242769D02*
X89459Y243159D01*
G01X119209Y199409D02*
Y249409D01*
G01X112349Y242769D02*
Y246050D01*
G01Y232769D02*
Y236050D01*
G01Y222769D02*
Y226050D01*
G01Y212769D02*
Y216050D01*
G01Y202769D02*
Y206050D01*
G01X112089Y205789D02*
Y203029D01*
G01Y215789D02*
Y213029D01*
G01Y225789D02*
Y223029D01*
G01Y235789D02*
Y233029D01*
G01Y245789D02*
Y243029D01*
G01X111959Y205659D02*
Y203159D01*
G01Y215659D02*
Y213159D01*
G01Y225659D02*
Y223159D01*
G01Y235659D02*
Y233159D01*
G01Y245659D02*
Y243159D01*
G01X109459Y205659D02*
Y203159D01*
G01Y215659D02*
Y213159D01*
G01Y225659D02*
Y223159D01*
G01Y235659D02*
Y233159D01*
G01Y245659D02*
Y243159D01*
G01X109329Y205789D02*
Y203029D01*
G01Y215789D02*
Y213029D01*
G01Y225789D02*
Y223029D01*
G01Y235789D02*
Y233029D01*
G01Y245789D02*
Y243029D01*
G01X109068Y206050D02*
Y202769D01*
G01Y216050D02*
Y212769D01*
G01Y226050D02*
Y222769D01*
G01Y236050D02*
Y232769D01*
G01Y246050D02*
Y242769D01*
G01X102349Y206050D02*
Y202769D01*
G01Y216050D02*
Y212769D01*
G01Y226050D02*
Y222769D01*
G01Y236050D02*
Y232769D01*
G01Y246050D02*
Y242769D01*
G01X102089Y205789D02*
Y203029D01*
G01Y215789D02*
Y213029D01*
G01Y225789D02*
Y223029D01*
G01Y235789D02*
Y233029D01*
G01Y245789D02*
Y243029D01*
G01X101959Y205659D02*
Y203159D01*
G01Y215659D02*
Y213159D01*
G01Y225659D02*
Y223159D01*
G01Y235659D02*
Y233159D01*
G01Y245659D02*
Y243159D01*
G01X99459D02*
Y245659D01*
G01Y233159D02*
Y235659D01*
G01Y223159D02*
Y225659D01*
G01Y213159D02*
Y215659D01*
G01Y203159D02*
Y205659D01*
G01X99329Y243029D02*
Y245789D01*
G01Y233029D02*
Y235789D01*
G01Y223029D02*
Y225789D01*
G01Y213029D02*
Y215789D01*
G01Y203029D02*
Y205789D01*
G01X99068Y242769D02*
Y246050D01*
G01Y232769D02*
Y236050D01*
G01Y222769D02*
Y226050D01*
G01Y212769D02*
Y216050D01*
G01Y202769D02*
Y206050D01*
G01X92349D02*
Y202769D01*
G01Y216050D02*
Y212769D01*
G01Y226050D02*
Y222769D01*
G01Y236050D02*
Y232769D01*
G01Y246050D02*
Y242769D01*
G01X92089Y205789D02*
Y203029D01*
G01Y215789D02*
Y213029D01*
G01Y225789D02*
Y223029D01*
G01Y235789D02*
Y233029D01*
G01Y245789D02*
Y243029D01*
G01X91959Y205659D02*
Y203159D01*
G01Y215659D02*
Y213159D01*
G01Y225659D02*
Y223159D01*
G01Y235659D02*
Y233159D01*
G01Y245659D02*
Y243159D01*
G01X89459D02*
Y245659D01*
G01Y233159D02*
Y235659D01*
G01Y223159D02*
Y225659D01*
G01Y213159D02*
Y215659D01*
G01Y203159D02*
Y205659D01*
G01X89329Y243029D02*
Y245789D01*
G01Y233029D02*
Y235789D01*
G01Y223029D02*
Y225789D01*
G01Y213029D02*
Y215789D01*
G01Y203029D02*
Y205789D01*
G01X89068Y242769D02*
Y246050D01*
G01Y232769D02*
Y236050D01*
G01Y222769D02*
Y226050D01*
G01Y212769D02*
Y216050D01*
G01Y202769D02*
Y206050D01*
G01X111959Y243159D02*
X112349Y242769D01*
G01X111959Y233159D02*
X112349Y232769D01*
G01X109068Y236050D02*
X109459Y235659D01*
G01X101959Y243159D02*
X102349Y242769D01*
G01X111959Y223159D02*
X112349Y222769D01*
G01X109068Y226050D02*
X109459Y225659D01*
G01X101959Y233159D02*
X102349Y232769D01*
G01X99068Y236050D02*
X99459Y235659D01*
G01X91959Y243159D02*
X92349Y242769D01*
G01X111959Y213159D02*
X112349Y212769D01*
G01X109068Y216050D02*
X109459Y215659D01*
G01X101959Y223159D02*
X102349Y222769D01*
G01X99068Y226050D02*
X99459Y225659D01*
G01X91959Y233159D02*
X92349Y232769D01*
G01X89068Y236050D02*
X89459Y235659D01*
G01X111959Y203159D02*
X112349Y202769D01*
G01X109068Y206050D02*
X109459Y205659D01*
G01X101959Y213159D02*
X102349Y212769D01*
G01X99068Y216050D02*
X99459Y215659D01*
G01X91959Y223159D02*
X92349Y222769D01*
G01X89068Y226050D02*
X89459Y225659D01*
G01X101959Y203159D02*
X102349Y202769D01*
G01X99068Y206050D02*
X99459Y205659D01*
G01X91959Y213159D02*
X92349Y212769D01*
G01X89068Y216050D02*
X89459Y215659D01*
G01X91959Y203159D02*
X92349Y202769D01*
G01X89068Y206050D02*
X89459Y205659D01*
G01X91959Y243159D02*
X89459D01*
G01X101959D02*
X99459D01*
G01X111959D02*
X109459D01*
G01X92089Y243029D02*
X89329D01*
G01X102089D02*
X99329D01*
G01X112089D02*
X109329D01*
G01X109068Y242769D02*
X112349D01*
G01X92349D02*
X89068D01*
G01X102349D02*
X99068D01*
G01Y236050D02*
X102349D01*
G01X89068D02*
X92349D01*
G01X112349D02*
X109068D01*
G01X109329Y235789D02*
X112089D01*
G01X99329D02*
X102089D01*
G01X89329D02*
X92089D01*
G01X109459Y235659D02*
X111959D01*
G01X99459D02*
X101959D01*
G01X89459D02*
X91959D01*
G01Y233159D02*
X89459D01*
G01X101959D02*
X99459D01*
G01X111959D02*
X109459D01*
G01X92089Y233029D02*
X89329D01*
G01X102089D02*
X99329D01*
G01X112089D02*
X109329D01*
G01X109068Y232769D02*
X112349D01*
G01X92349D02*
X89068D01*
G01X102349D02*
X99068D01*
G01Y226050D02*
X102349D01*
G01X89068D02*
X92349D01*
G01X112349D02*
X109068D01*
G01X109329Y225789D02*
X112089D01*
G01X99329D02*
X102089D01*
G01X89329D02*
X92089D01*
G01X109459Y225659D02*
X111959D01*
G01X99459D02*
X101959D01*
G01X89459D02*
X91959D01*
G01Y223159D02*
X89459D01*
G01X101959D02*
X99459D01*
G01X111959D02*
X109459D01*
G01X92089Y223029D02*
X89329D01*
G01X102089D02*
X99329D01*
G01X112089D02*
X109329D01*
G01X109068Y222769D02*
X112349D01*
G01X92349D02*
X89068D01*
G01X102349D02*
X99068D01*
G01Y216050D02*
X102349D01*
G01X89068D02*
X92349D01*
G01X112349D02*
X109068D01*
G01X109329Y215789D02*
X112089D01*
G01X99329D02*
X102089D01*
G01X89329D02*
X92089D01*
G01X109459Y215659D02*
X111959D01*
G01X99459D02*
X101959D01*
G01X89459D02*
X91959D01*
G01Y213159D02*
X89459D01*
G01X101959D02*
X99459D01*
G01X111959D02*
X109459D01*
G01X92089Y213029D02*
X89329D01*
G01X102089D02*
X99329D01*
G01X112089D02*
X109329D01*
G01X109068Y212769D02*
X112349D01*
G01X92349D02*
X89068D01*
G01X102349D02*
X99068D01*
G01Y206050D02*
X102349D01*
G01X89068D02*
X92349D01*
G01X112349D02*
X109068D01*
G01X109329Y205789D02*
X112089D01*
G01X99329D02*
X102089D01*
G01X89329D02*
X92089D01*
G01X109459Y205659D02*
X111959D01*
G01X99459D02*
X101959D01*
G01X89459D02*
X91959D01*
G01Y203159D02*
X89459D01*
G01X101959D02*
X99459D01*
G01X111959D02*
X109459D01*
G01X92089Y203029D02*
X89329D01*
G01X102089D02*
X99329D01*
G01X112089D02*
X109329D01*
G01X109068Y202769D02*
X112349D01*
G01X92349D02*
X89068D01*
G01X102349D02*
X99068D01*
G01X119209Y199409D02*
X121404D01*
G01X108956Y257910D02*
G03X112461I1753J-981D01*
G01X108956Y277910D02*
G03X112461I1753J-981D01*
G01X112438Y265909D02*
G03X108979I-1730J1020D01*
G01X112438Y285909D02*
G03X108979I-1730J1020D01*
G01X98956Y257910D02*
G03X102461I1753J-981D01*
G01X98956Y277910D02*
G03X102461I1753J-981D01*
G01X102438Y265909D02*
G03X98979I-1730J1020D01*
G01X102438Y285909D02*
G03X98979I-1730J1020D01*
G01X88956Y277910D02*
G03X92461I1753J-981D01*
G01X92438Y285909D02*
G03X88979I-1729J1020D01*
G01X88956Y257910D02*
G03X92461I1753J-981D01*
G01X92438Y265909D02*
G03X88979I-1729J1020D01*
G01X111959Y245659D02*
X112349Y246050D01*
G01X102349D02*
X101959Y245659D01*
G01X92349Y246050D02*
X91959Y245659D01*
G01X119409Y249409D02*
Y294409D01*
G01X113339Y265909D02*
Y257909D01*
G01Y285909D02*
Y277909D01*
G01X111959Y285909D02*
Y287909D01*
G01Y275909D02*
Y277909D01*
G01Y265909D02*
Y267909D01*
G01Y255909D02*
Y257909D01*
G01X109459D02*
Y255909D01*
G01Y267909D02*
Y265909D01*
G01Y277909D02*
Y275909D01*
G01Y287909D02*
Y285909D01*
G01X109414Y257909D02*
Y255909D01*
G01Y267909D02*
Y265909D01*
G01Y277909D02*
Y275909D01*
G01Y287909D02*
Y285909D01*
G01X104622Y257909D02*
Y255909D01*
G01Y267909D02*
Y265909D01*
G01Y277909D02*
Y275909D01*
G01Y287909D02*
Y285909D01*
G01X101959D02*
Y287909D01*
G01Y275909D02*
Y277909D01*
G01Y265909D02*
Y267909D01*
G01Y255909D02*
Y257909D01*
G01X99459D02*
Y255909D01*
G01Y267909D02*
Y265909D01*
G01Y277909D02*
Y275909D01*
G01Y287909D02*
Y285909D01*
G01X91959D02*
Y287909D01*
G01Y275909D02*
Y277909D01*
G01Y265909D02*
Y267909D01*
G01Y255909D02*
Y257909D01*
G01X89459D02*
Y255909D01*
G01Y267909D02*
Y265909D01*
G01Y277909D02*
Y275909D01*
G01Y287909D02*
Y285909D01*
G01X109068Y246050D02*
X109459Y245659D01*
G01X99068Y246050D02*
X99459Y245659D01*
G01X89068Y246050D02*
X89459Y245659D01*
G01X111959Y287909D02*
X109459D01*
G01Y275909D02*
X111959D01*
G01Y267909D02*
X109459D01*
G01Y255909D02*
X111959D01*
G01X119209Y249409D02*
X121404D01*
G01X99068Y246050D02*
X102349D01*
G01X89068D02*
X92349D01*
G01X112349D02*
X109068D01*
G01X109329Y245789D02*
X112089D01*
G01X99329D02*
X102089D01*
G01X89329D02*
X92089D01*
G01X109459Y245659D02*
X111959D01*
G01X99459D02*
X101959D01*
G01X89459D02*
X91959D01*
G01X94409Y303409D02*
Y339409D01*
G01Y302909D02*
Y303409D01*
G01X86509Y305409D02*
Y298409D01*
G01X163306Y339409D02*
X135906D01*
G01X94409Y310909D02*
X124409D01*
G01X163306Y309409D02*
X135906D01*
G01X124409Y303409D02*
X94409D01*
G01X124409Y302909D02*
X94409D01*
G01X86509Y298409D02*
X121409D01*
G01X113189Y568071D02*
Y566181D01*
G01Y575551D02*
Y573661D01*
G01X112598Y568071D02*
Y566181D01*
G01Y575551D02*
Y573661D01*
G01X112405Y568071D02*
Y566181D01*
G01Y575551D02*
Y573661D01*
G01X112270Y568071D02*
Y566181D01*
G01Y575551D02*
Y573661D01*
G01X111823Y568071D02*
Y566181D01*
G01Y575551D02*
Y573661D01*
G01X111689Y568071D02*
Y566181D01*
G01Y575551D02*
Y573661D01*
G01X111495Y568071D02*
Y566181D01*
G01Y575551D02*
Y573661D01*
G01X111024Y564961D02*
Y576772D01*
G01X105512D02*
Y564961D01*
G01X105041Y571811D02*
Y569921D01*
G01X104847Y571811D02*
Y569921D01*
G01X104712Y571811D02*
Y569921D01*
G01X104265Y571811D02*
Y569921D01*
G01X104131Y571811D02*
Y569921D01*
G01X103937Y571811D02*
Y569921D01*
G01X103346Y571811D02*
Y569921D01*
G01X111024Y576772D02*
X105512D01*
G01X113189Y575551D02*
X111024D01*
G01X113189Y573661D02*
X111024D01*
G01X105512Y571811D02*
X103346D01*
G01X105512Y569921D02*
X103346D01*
G01X113189Y568071D02*
X111024D01*
G01X113189Y566181D02*
X111024D01*
G01X105512Y564961D02*
X111024D01*
G01X123087Y1001721D02*
Y951721D01*
G01X108713Y1001721D02*
X137463D01*
G01X111024Y1265748D02*
X105512D01*
G01X113189Y1264528D02*
X111024D01*
G01X113189Y1262638D02*
X111024D01*
G01X105512Y1260787D02*
X103346D01*
G01X105512Y1258898D02*
X103346D01*
G01X113189Y1257047D02*
X111024D01*
G01X113189Y1255157D02*
X111024D01*
G01X105512Y1253937D02*
X111024D01*
G01X113189Y1257047D02*
Y1255157D01*
G01Y1264528D02*
Y1262638D01*
G01X112598Y1257047D02*
Y1255157D01*
G01Y1264528D02*
Y1262638D01*
G01X112405Y1257047D02*
Y1255157D01*
G01Y1264528D02*
Y1262638D01*
G01X112270Y1257047D02*
Y1255157D01*
G01Y1264528D02*
Y1262638D01*
G01X111823Y1257047D02*
Y1255157D01*
G01Y1264528D02*
Y1262638D01*
G01X111689Y1257047D02*
Y1255157D01*
G01Y1264528D02*
Y1262638D01*
G01X111495Y1257047D02*
Y1255157D01*
G01Y1264528D02*
Y1262638D01*
G01X111024Y1253937D02*
Y1265748D01*
G01X105512D02*
Y1253937D01*
G01X105041Y1260787D02*
Y1258898D01*
G01X104847Y1260787D02*
Y1258898D01*
G01X104712Y1260787D02*
Y1258898D01*
G01X104265Y1260787D02*
Y1258898D01*
G01X104131Y1260787D02*
Y1258898D01*
G01X103937Y1260787D02*
Y1258898D01*
G01X103346Y1260787D02*
Y1258898D01*
G01X188384Y1689960D02*
X134447D01*
G01X188384D02*
X134447D01*
G01D02*
Y1772125D01*
G01Y1689960D02*
Y1772125D01*
G01X123424D02*
Y1689960D01*
G01Y1772125D02*
Y1689960D01*
G01X104329Y1747834D02*
G03I-7874J0D01*
G01X104920D02*
G03I-8465J0D01*
G01X105314D02*
G03I-8859J0D01*
G01X105904D02*
G03I-9449J0D01*
G01X106199D02*
G03I-9744J0D01*
G01X106298D02*
G03I-9843J0D01*
G01D02*
G03I-9843J0D01*
G01X119093Y1785511D02*
G03Y1772125I0J-6693D01*
G01Y1785511D02*
G03Y1772125I0J-6693D01*
G01X134447D02*
X138778D01*
G01X134447D02*
X138778D01*
G01X123424D02*
X119093D01*
G01X123424D02*
X119093D01*
G01X134447Y1769881D02*
X147873D01*
G01X123424D02*
X134447D01*
G01X109999D02*
X123424D01*
G01X109999Y1787755D02*
Y1769881D01*
G01X113937Y1782244D02*
Y1775394D01*
G01X120905Y1778819D02*
G03I-1968J0D01*
G01X120196Y1777559D02*
Y1780079D01*
G01X116417Y1779354D02*
X116599Y1779571D01*
G01Y1779323D02*
X116417Y1779105D01*
G01D02*
Y1779354D01*
G01X116599Y1778111D02*
Y1779323D01*
G01X116782Y1779571D02*
Y1778111D01*
G01X117677Y1780079D02*
Y1777559D01*
G01D02*
X120196D01*
G01X116782Y1778111D02*
X116599D01*
G01Y1779571D02*
X116782D01*
G01X127677Y1780079D02*
Y1777559D01*
G01D02*
X130196D01*
G01X130905Y1778819D02*
G03I-1968J0D01*
G01X113937Y1775394D02*
X114846Y1773819D01*
G01X123027D02*
X123937Y1775394D01*
G01D02*
X124846Y1773819D01*
G01X114846D02*
X123027D01*
G01X124846D02*
X133027D01*
G01X130196Y1777559D02*
Y1780079D01*
G01X133027Y1773819D02*
X133937Y1775394D01*
G01D02*
X134846Y1773819D01*
G01D02*
X143027D01*
G01X104329Y1823031D02*
G03I-7874J0D01*
G01X104920D02*
G03I-8465J0D01*
G01X105314D02*
G03I-8859J0D01*
G01X105904D02*
G03I-9449J0D01*
G01X106199D02*
G03I-9744J0D01*
G01X106298D02*
G03I-9843J0D01*
G01D02*
G03I-9843J0D01*
G01X123424Y1787755D02*
X109999D01*
G01X134447D02*
X123424D01*
G01X147873D02*
X134447D01*
G01Y1785511D02*
X138778D01*
G01X134447D02*
X138778D01*
G01X123424D02*
X119093D01*
G01X123424D02*
X119093D01*
G01X134447D02*
Y1856889D01*
G01Y1785511D02*
Y1856889D01*
G01X123424D02*
Y1785511D01*
G01Y1856889D02*
Y1785511D01*
G01X114846Y1783819D02*
X113937Y1782244D01*
G01X120196Y1780079D02*
X117677D01*
G01X123027Y1783819D02*
X114846D01*
G01X124846D02*
X123937Y1782244D01*
G01D02*
X123027Y1783819D01*
G01X130196Y1780079D02*
X127677D01*
G01X133027Y1783819D02*
X124846D01*
G01X134846D02*
X133937Y1782244D01*
G01D02*
X133027Y1783819D01*
G01X143027D02*
X134846D01*
G01X134447Y1856889D02*
X188384D01*
G01X134447D02*
X188384D01*
G01X118011Y1968504D02*
X142520D01*
G01X109377D02*
X110137D01*
G01D02*
G03X118011I3937J0D01*
G01X110137D02*
G03X118011I3937J0D01*
G01X114074D02*
Y1968110D01*
G01Y1968504D02*
Y1968898D01*
G01X113582Y1968504D02*
X114566D01*
G01X131433Y2112671D02*
Y2093734D01*
G01X168110Y31496D02*
G03Y39370I0J3937D01*
G01Y31496D02*
G03Y39370I0J3937D01*
G01X186024Y78740D02*
G03I-6890J0D01*
G01X154508Y139409D02*
G03I-4902J0D01*
G01X155706Y119409D02*
G03I-6100J0D01*
G01X155866D02*
G03I-6260J0D01*
G01X163306Y109409D02*
Y145409D01*
G01X150956Y144359D02*
Y134459D01*
G01X148256D02*
Y144359D01*
G01X193306Y137909D02*
X163306D01*
G01X150956Y134459D02*
X148256D01*
G01X177877Y182910D02*
G03X181336I1730J-1020D01*
G01X181358Y170909D02*
G03X177854I-1752J981D01*
G01X181358Y190909D02*
G03X177854I-1752J981D01*
G01X167877Y182910D02*
G03X171336I1730J-1020D01*
G01X171358Y170909D02*
G03X167854I-1752J981D01*
G01X171358Y190909D02*
G03X167854I-1752J981D01*
G01X157877Y182910D02*
G03X161336I1730J-1020D01*
G01X161358Y170909D02*
G03X157854I-1752J981D01*
G01X161358Y190909D02*
G03X157854I-1752J981D01*
G01X177877Y162910D02*
G03X181336I1730J-1020D01*
G01X167877D02*
G03X171336I1730J-1020D01*
G01X157877D02*
G03X161336I1730J-1020D01*
G01X147877D02*
G03X151336I1730J-1020D01*
G01X147877Y182910D02*
G03X151336I1730J-1020D01*
G01X151358Y170909D02*
G03X147854I-1752J981D01*
G01X151358Y190909D02*
G03X147854I-1752J981D01*
G01X182236Y170909D02*
Y162909D01*
G01Y190909D02*
Y182909D01*
G01X180856Y190909D02*
Y192909D01*
G01Y180909D02*
Y182909D01*
G01Y170909D02*
Y172909D01*
G01Y160909D02*
Y162909D01*
G01X178356D02*
Y160909D01*
G01Y172909D02*
Y170909D01*
G01Y182909D02*
Y180909D01*
G01Y192909D02*
Y190909D01*
G01X178312Y162909D02*
Y160909D01*
G01Y172909D02*
Y170909D01*
G01Y182909D02*
Y180909D01*
G01Y192909D02*
Y190909D01*
G01X173519Y162909D02*
Y160909D01*
G01Y172909D02*
Y170909D01*
G01Y182909D02*
Y180909D01*
G01Y192909D02*
Y190909D01*
G01X170856D02*
Y192909D01*
G01Y180909D02*
Y182909D01*
G01Y170909D02*
Y172909D01*
G01Y160909D02*
Y162909D01*
G01X168356D02*
Y160909D01*
G01Y172909D02*
Y170909D01*
G01Y182909D02*
Y180909D01*
G01Y192909D02*
Y190909D01*
G01X163306Y145409D02*
Y145909D01*
G01X160856Y190909D02*
Y192909D01*
G01Y180909D02*
Y182909D01*
G01Y170909D02*
Y172909D01*
G01Y160909D02*
Y162909D01*
G01X158356D02*
Y160909D01*
G01Y172909D02*
Y170909D01*
G01Y182909D02*
Y180909D01*
G01Y192909D02*
Y190909D01*
G01X155406Y150409D02*
Y143409D01*
G01X152243Y162909D02*
Y160909D01*
G01Y172909D02*
Y170909D01*
G01Y182909D02*
Y180909D01*
G01Y192909D02*
Y190909D01*
G01X150856D02*
Y192909D01*
G01Y180909D02*
Y182909D01*
G01Y170909D02*
Y172909D01*
G01Y160909D02*
Y162909D01*
G01X148356D02*
Y160909D01*
G01Y172909D02*
Y170909D01*
G01Y182909D02*
Y180909D01*
G01Y192909D02*
Y190909D01*
G01X147451D02*
Y192909D01*
G01Y180909D02*
Y182909D01*
G01Y170909D02*
Y172909D01*
G01Y160909D02*
Y162909D01*
G01X146836Y182909D02*
Y190909D01*
G01Y162909D02*
Y170909D01*
G01X140906Y154409D02*
Y199409D01*
G01X138906Y143409D02*
Y305409D01*
G01X147451Y192909D02*
X178312D01*
G01X180856D02*
X178356D01*
G01X146836Y190909D02*
X182236D01*
G01X146836Y182909D02*
X182236D01*
G01X178356Y180909D02*
X180856D01*
G01X147451D02*
X178312D01*
G01X147451Y172909D02*
X178312D01*
G01X180856D02*
X178356D01*
G01X146836Y170909D02*
X182236D01*
G01X146836Y162909D02*
X182236D01*
G01X178356Y160909D02*
X180856D01*
G01X147451D02*
X178312D01*
G01X138906Y154409D02*
X190306D01*
G01Y150409D02*
X155406D01*
G01X163306Y145909D02*
X193306D01*
G01X163306Y145409D02*
X193306D01*
G01X148256Y144359D02*
X150956D01*
G01X155406Y143409D02*
X138906D01*
G01X181614Y234409D02*
G03I-2008J0D01*
G01Y244409D02*
G03I-2008J0D01*
G01X171614Y234409D02*
G03I-2008J0D01*
G01Y244409D02*
G03I-2008J0D01*
G01X181614Y204409D02*
G03I-2008J0D01*
G01Y214409D02*
G03I-2008J0D01*
G01Y224409D02*
G03I-2008J0D01*
G01X171614Y204409D02*
G03I-2008J0D01*
G01Y214409D02*
G03I-2008J0D01*
G01Y224409D02*
G03I-2008J0D01*
G01X161614Y234409D02*
G03I-2008J0D01*
G01Y244409D02*
G03I-2008J0D01*
G01Y204409D02*
G03I-2008J0D01*
G01Y214409D02*
G03I-2008J0D01*
G01Y224409D02*
G03I-2008J0D01*
G01X151614Y204409D02*
G03I-2008J0D01*
G01Y214409D02*
G03I-2008J0D01*
G01Y224409D02*
G03I-2008J0D01*
G01Y234409D02*
G03I-2008J0D01*
G01Y244409D02*
G03I-2008J0D01*
G01X180856Y205659D02*
X181247Y206050D01*
G01X178356Y203159D02*
X177966Y202769D01*
G01X180856Y215659D02*
X181247Y216050D01*
G01X167966Y202769D02*
X168356Y203159D01*
G01X171247Y206050D02*
X170856Y205659D01*
G01X178356Y213159D02*
X177966Y212769D01*
G01X180856Y225659D02*
X181247Y226050D01*
G01X167966Y212769D02*
X168356Y213159D01*
G01X157966Y202769D02*
X158356Y203159D01*
G01X161247Y206050D02*
X160856Y205659D01*
G01X171247Y216050D02*
X170856Y215659D01*
G01X178356Y223159D02*
X177966Y222769D01*
G01X180856Y235659D02*
X181247Y236050D01*
G01X167966Y222769D02*
X168356Y223159D01*
G01X157966Y212769D02*
X158356Y213159D01*
G01X147966Y202769D02*
X148356Y203159D01*
G01X151247Y206050D02*
X150856Y205659D01*
G01X161247Y216050D02*
X160856Y215659D01*
G01X171247Y226050D02*
X170856Y225659D01*
G01X178356Y233159D02*
X177966Y232769D01*
G01X167966D02*
X168356Y233159D01*
G01X157966Y222769D02*
X158356Y223159D01*
G01X147966Y212769D02*
X148356Y213159D01*
G01X151247Y216050D02*
X150856Y215659D01*
G01X161247Y226050D02*
X160856Y225659D01*
G01X171247Y236050D02*
X170856Y235659D01*
G01X178356Y243159D02*
X177966Y242769D01*
G01X167966D02*
X168356Y243159D01*
G01X157966Y232769D02*
X158356Y233159D01*
G01X147966Y222769D02*
X148356Y223159D01*
G01X151247Y226050D02*
X150856Y225659D01*
G01X161247Y236050D02*
X160856Y235659D01*
G01X157966Y242769D02*
X158356Y243159D01*
G01X147966Y232769D02*
X148356Y233159D01*
G01X151247Y236050D02*
X150856Y235659D01*
G01X147966Y242769D02*
X148356Y243159D01*
G01X181247Y242769D02*
Y246050D01*
G01Y232769D02*
Y236050D01*
G01Y222769D02*
Y226050D01*
G01Y212769D02*
Y216050D01*
G01Y202769D02*
Y206050D01*
G01X180986Y205789D02*
Y203029D01*
G01Y215789D02*
Y213029D01*
G01Y225789D02*
Y223029D01*
G01Y235789D02*
Y233029D01*
G01Y245789D02*
Y243029D01*
G01X180856Y205659D02*
Y203159D01*
G01Y215659D02*
Y213159D01*
G01Y225659D02*
Y223159D01*
G01Y235659D02*
Y233159D01*
G01Y245659D02*
Y243159D01*
G01X178356Y205659D02*
Y203159D01*
G01Y215659D02*
Y213159D01*
G01Y225659D02*
Y223159D01*
G01Y235659D02*
Y233159D01*
G01Y245659D02*
Y243159D01*
G01X178226Y205789D02*
Y203029D01*
G01Y215789D02*
Y213029D01*
G01Y225789D02*
Y223029D01*
G01Y235789D02*
Y233029D01*
G01Y245789D02*
Y243029D01*
G01X177966Y206050D02*
Y202769D01*
G01Y216050D02*
Y212769D01*
G01Y226050D02*
Y222769D01*
G01Y236050D02*
Y232769D01*
G01Y246050D02*
Y242769D01*
G01X171247Y206050D02*
Y202769D01*
G01Y216050D02*
Y212769D01*
G01Y226050D02*
Y222769D01*
G01Y236050D02*
Y232769D01*
G01Y246050D02*
Y242769D01*
G01X170986Y205789D02*
Y203029D01*
G01Y215789D02*
Y213029D01*
G01Y225789D02*
Y223029D01*
G01Y235789D02*
Y233029D01*
G01Y245789D02*
Y243029D01*
G01X170856Y205659D02*
Y203159D01*
G01Y215659D02*
Y213159D01*
G01Y225659D02*
Y223159D01*
G01Y235659D02*
Y233159D01*
G01Y245659D02*
Y243159D01*
G01X168356D02*
Y245659D01*
G01Y233159D02*
Y235659D01*
G01Y223159D02*
Y225659D01*
G01Y213159D02*
Y215659D01*
G01Y203159D02*
Y205659D01*
G01X168226Y243029D02*
Y245789D01*
G01Y233029D02*
Y235789D01*
G01Y223029D02*
Y225789D01*
G01Y213029D02*
Y215789D01*
G01Y203029D02*
Y205789D01*
G01X167966Y242769D02*
Y246050D01*
G01Y232769D02*
Y236050D01*
G01Y222769D02*
Y226050D01*
G01Y212769D02*
Y216050D01*
G01Y202769D02*
Y206050D01*
G01X161247D02*
Y202769D01*
G01Y216050D02*
Y212769D01*
G01Y226050D02*
Y222769D01*
G01Y236050D02*
Y232769D01*
G01Y246050D02*
Y242769D01*
G01X160986Y205789D02*
Y203029D01*
G01Y215789D02*
Y213029D01*
G01Y225789D02*
Y223029D01*
G01Y235789D02*
Y233029D01*
G01Y245789D02*
Y243029D01*
G01X160856Y205659D02*
Y203159D01*
G01Y215659D02*
Y213159D01*
G01Y225659D02*
Y223159D01*
G01Y235659D02*
Y233159D01*
G01Y245659D02*
Y243159D01*
G01X158356D02*
Y245659D01*
G01Y233159D02*
Y235659D01*
G01Y223159D02*
Y225659D01*
G01Y213159D02*
Y215659D01*
G01Y203159D02*
Y205659D01*
G01X158226Y243029D02*
Y245789D01*
G01Y233029D02*
Y235789D01*
G01Y223029D02*
Y225789D01*
G01Y213029D02*
Y215789D01*
G01Y203029D02*
Y205789D01*
G01X157966Y242769D02*
Y246050D01*
G01Y232769D02*
Y236050D01*
G01Y222769D02*
Y226050D01*
G01Y212769D02*
Y216050D01*
G01Y202769D02*
Y206050D01*
G01X151247D02*
Y202769D01*
G01Y216050D02*
Y212769D01*
G01Y226050D02*
Y222769D01*
G01Y236050D02*
Y232769D01*
G01Y246050D02*
Y242769D01*
G01X150986Y205789D02*
Y203029D01*
G01Y215789D02*
Y213029D01*
G01Y225789D02*
Y223029D01*
G01Y235789D02*
Y233029D01*
G01Y245789D02*
Y243029D01*
G01X150856Y205659D02*
Y203159D01*
G01Y215659D02*
Y213159D01*
G01Y225659D02*
Y223159D01*
G01Y235659D02*
Y233159D01*
G01Y245659D02*
Y243159D01*
G01X148356D02*
Y245659D01*
G01Y233159D02*
Y235659D01*
G01Y223159D02*
Y225659D01*
G01Y213159D02*
Y215659D01*
G01Y203159D02*
Y205659D01*
G01X148226Y243029D02*
Y245789D01*
G01Y233029D02*
Y235789D01*
G01Y223029D02*
Y225789D01*
G01Y213029D02*
Y215789D01*
G01Y203029D02*
Y205789D01*
G01X147966Y242769D02*
Y246050D01*
G01Y232769D02*
Y236050D01*
G01Y222769D02*
Y226050D01*
G01Y212769D02*
Y216050D01*
G01Y202769D02*
Y206050D01*
G01X141106Y199409D02*
Y249409D01*
G01X180856Y243159D02*
X181247Y242769D01*
G01X180856Y233159D02*
X181247Y232769D01*
G01X177966Y236050D02*
X178356Y235659D01*
G01X170856Y243159D02*
X171247Y242769D01*
G01X180856Y223159D02*
X181247Y222769D01*
G01X177966Y226050D02*
X178356Y225659D01*
G01X170856Y233159D02*
X171247Y232769D01*
G01X167966Y236050D02*
X168356Y235659D01*
G01X160856Y243159D02*
X161247Y242769D01*
G01X180856Y213159D02*
X181247Y212769D01*
G01X177966Y216050D02*
X178356Y215659D01*
G01X170856Y223159D02*
X171247Y222769D01*
G01X167966Y226050D02*
X168356Y225659D01*
G01X160856Y233159D02*
X161247Y232769D01*
G01X157966Y236050D02*
X158356Y235659D01*
G01X150856Y243159D02*
X151247Y242769D01*
G01X180856Y203159D02*
X181247Y202769D01*
G01X177966Y206050D02*
X178356Y205659D01*
G01X170856Y213159D02*
X171247Y212769D01*
G01X167966Y216050D02*
X168356Y215659D01*
G01X160856Y223159D02*
X161247Y222769D01*
G01X157966Y226050D02*
X158356Y225659D01*
G01X150856Y233159D02*
X151247Y232769D01*
G01X147966Y236050D02*
X148356Y235659D01*
G01X170856Y203159D02*
X171247Y202769D01*
G01X167966Y206050D02*
X168356Y205659D01*
G01X160856Y213159D02*
X161247Y212769D01*
G01X157966Y216050D02*
X158356Y215659D01*
G01X150856Y223159D02*
X151247Y222769D01*
G01X147966Y226050D02*
X148356Y225659D01*
G01X160856Y203159D02*
X161247Y202769D01*
G01X157966Y206050D02*
X158356Y205659D01*
G01X150856Y213159D02*
X151247Y212769D01*
G01X147966Y216050D02*
X148356Y215659D01*
G01X150856Y203159D02*
X151247Y202769D01*
G01X147966Y206050D02*
X148356Y205659D01*
G01X150856Y243159D02*
X148356D01*
G01X160856D02*
X158356D01*
G01X170856D02*
X168356D01*
G01X180856D02*
X178356D01*
G01X150986Y243029D02*
X148226D01*
G01X160986D02*
X158226D01*
G01X170986D02*
X168226D01*
G01X180986D02*
X178226D01*
G01X177966Y242769D02*
X181247D01*
G01X151247D02*
X147966D01*
G01X161247D02*
X157966D01*
G01X171247D02*
X167966D01*
G01Y236050D02*
X171247D01*
G01X157966D02*
X161247D01*
G01X147966D02*
X151247D01*
G01X181247D02*
X177966D01*
G01X178226Y235789D02*
X180986D01*
G01X168226D02*
X170986D01*
G01X158226D02*
X160986D01*
G01X148226D02*
X150986D01*
G01X178356Y235659D02*
X180856D01*
G01X168356D02*
X170856D01*
G01X158356D02*
X160856D01*
G01X148356D02*
X150856D01*
G01Y233159D02*
X148356D01*
G01X160856D02*
X158356D01*
G01X170856D02*
X168356D01*
G01X180856D02*
X178356D01*
G01X150986Y233029D02*
X148226D01*
G01X160986D02*
X158226D01*
G01X170986D02*
X168226D01*
G01X180986D02*
X178226D01*
G01X177966Y232769D02*
X181247D01*
G01X151247D02*
X147966D01*
G01X161247D02*
X157966D01*
G01X171247D02*
X167966D01*
G01Y226050D02*
X171247D01*
G01X157966D02*
X161247D01*
G01X147966D02*
X151247D01*
G01X181247D02*
X177966D01*
G01X178226Y225789D02*
X180986D01*
G01X168226D02*
X170986D01*
G01X158226D02*
X160986D01*
G01X148226D02*
X150986D01*
G01X178356Y225659D02*
X180856D01*
G01X168356D02*
X170856D01*
G01X158356D02*
X160856D01*
G01X148356D02*
X150856D01*
G01Y223159D02*
X148356D01*
G01X160856D02*
X158356D01*
G01X170856D02*
X168356D01*
G01X180856D02*
X178356D01*
G01X150986Y223029D02*
X148226D01*
G01X160986D02*
X158226D01*
G01X170986D02*
X168226D01*
G01X180986D02*
X178226D01*
G01X177966Y222769D02*
X181247D01*
G01X151247D02*
X147966D01*
G01X161247D02*
X157966D01*
G01X171247D02*
X167966D01*
G01Y216050D02*
X171247D01*
G01X157966D02*
X161247D01*
G01X147966D02*
X151247D01*
G01X181247D02*
X177966D01*
G01X178226Y215789D02*
X180986D01*
G01X168226D02*
X170986D01*
G01X158226D02*
X160986D01*
G01X148226D02*
X150986D01*
G01X178356Y215659D02*
X180856D01*
G01X168356D02*
X170856D01*
G01X158356D02*
X160856D01*
G01X148356D02*
X150856D01*
G01Y213159D02*
X148356D01*
G01X160856D02*
X158356D01*
G01X170856D02*
X168356D01*
G01X180856D02*
X178356D01*
G01X150986Y213029D02*
X148226D01*
G01X160986D02*
X158226D01*
G01X170986D02*
X168226D01*
G01X180986D02*
X178226D01*
G01X177966Y212769D02*
X181247D01*
G01X151247D02*
X147966D01*
G01X161247D02*
X157966D01*
G01X171247D02*
X167966D01*
G01Y206050D02*
X171247D01*
G01X157966D02*
X161247D01*
G01X147966D02*
X151247D01*
G01X181247D02*
X177966D01*
G01X178226Y205789D02*
X180986D01*
G01X168226D02*
X170986D01*
G01X158226D02*
X160986D01*
G01X148226D02*
X150986D01*
G01X178356Y205659D02*
X180856D01*
G01X168356D02*
X170856D01*
G01X158356D02*
X160856D01*
G01X148356D02*
X150856D01*
G01Y203159D02*
X148356D01*
G01X160856D02*
X158356D01*
G01X170856D02*
X168356D01*
G01X180856D02*
X178356D01*
G01X150986Y203029D02*
X148226D01*
G01X160986D02*
X158226D01*
G01X170986D02*
X168226D01*
G01X180986D02*
X178226D01*
G01X177966Y202769D02*
X181247D01*
G01X151247D02*
X147966D01*
G01X161247D02*
X157966D01*
G01X171247D02*
X167966D01*
G01X138911Y199409D02*
X141106D01*
G01X177854Y277910D02*
G03X181358I1752J-981D01*
G01X181336Y265909D02*
G03X177877I-1729J1020D01*
G01X181336Y285909D02*
G03X177877I-1729J1020D01*
G01X177854Y257910D02*
G03X181358I1752J-981D01*
G01X167854Y277910D02*
G03X171358I1752J-981D01*
G01X171336Y265909D02*
G03X167877I-1729J1020D01*
G01X171336Y285909D02*
G03X167877I-1729J1020D01*
G01X167854Y257910D02*
G03X171358I1752J-981D01*
G01X157854D02*
G03X161358I1752J-981D01*
G01X157854Y277910D02*
G03X161358I1752J-981D01*
G01X161336Y265909D02*
G03X157877I-1729J1020D01*
G01X161336Y285909D02*
G03X157877I-1729J1020D01*
G01X147854Y257910D02*
G03X151358I1752J-981D01*
G01X147854Y277910D02*
G03X151358I1752J-981D01*
G01X151336Y265909D02*
G03X147877I-1730J1020D01*
G01X151336Y285909D02*
G03X147877I-1730J1020D01*
G01X152744Y286756D02*
X152668Y286731D01*
G01Y286879D02*
X152744Y286904D01*
G01X152844Y286830D02*
X152744Y286756D01*
G01Y286904D02*
X152794Y286953D01*
G01X180856Y245659D02*
X181247Y246050D01*
G01X171247D02*
X170856Y245659D01*
G01X161247Y246050D02*
X160856Y245659D01*
G01X151247Y246050D02*
X150856Y245659D01*
G01X152920Y286928D02*
X152844Y286830D01*
G01X152794Y286953D02*
X152819Y287027D01*
G01X152945Y287051D02*
X152920Y286928D01*
G01X182236Y265909D02*
Y257909D01*
G01Y285909D02*
Y277909D01*
G01X180856Y285909D02*
Y287909D01*
G01Y275909D02*
Y277909D01*
G01Y265909D02*
Y267909D01*
G01Y255909D02*
Y257909D01*
G01X178356D02*
Y255909D01*
G01Y267909D02*
Y265909D01*
G01Y277909D02*
Y275909D01*
G01Y287909D02*
Y285909D01*
G01X178312Y257909D02*
Y255909D01*
G01Y267909D02*
Y265909D01*
G01Y277909D02*
Y275909D01*
G01Y287909D02*
Y285909D01*
G01X173519Y257909D02*
Y255909D01*
G01Y267909D02*
Y265909D01*
G01Y277909D02*
Y275909D01*
G01Y287909D02*
Y285909D01*
G01X170856D02*
Y287909D01*
G01Y275909D02*
Y277909D01*
G01Y265909D02*
Y267909D01*
G01Y255909D02*
Y257909D01*
G01X168356D02*
Y255909D01*
G01Y267909D02*
Y265909D01*
G01Y277909D02*
Y275909D01*
G01Y287909D02*
Y285909D01*
G01X160856D02*
Y287909D01*
G01Y275909D02*
Y277909D01*
G01Y265909D02*
Y267909D01*
G01Y255909D02*
Y257909D01*
G01X158356D02*
Y255909D01*
G01Y267909D02*
Y265909D01*
G01Y277909D02*
Y275909D01*
G01Y287909D02*
Y285909D01*
G01X152945Y286387D02*
Y286239D01*
G01Y287642D02*
Y287051D01*
G01X152819Y287027D02*
Y287494D01*
G01X152442D02*
Y287027D01*
G01X152292Y287051D02*
Y287494D01*
G01X152243Y257909D02*
Y255909D01*
G01Y267909D02*
Y265909D01*
G01Y277909D02*
Y275909D01*
G01Y287909D02*
Y285909D01*
G01X151764Y287494D02*
Y287642D01*
G01Y286239D02*
Y286387D01*
G01X150856Y285909D02*
Y287909D01*
G01Y275909D02*
Y277909D01*
G01Y265909D02*
Y267909D01*
G01Y255909D02*
Y257909D01*
G01X148356D02*
Y255909D01*
G01Y267909D02*
Y265909D01*
G01Y277909D02*
Y275909D01*
G01Y287909D02*
Y285909D01*
G01X147451D02*
Y287909D01*
G01Y275909D02*
Y277909D01*
G01Y265909D02*
Y267909D01*
G01Y255909D02*
Y257909D01*
G01X146836Y277909D02*
Y285909D01*
G01Y257909D02*
Y265909D01*
G01X140906Y249409D02*
Y294409D01*
G01X152317Y286928D02*
X152292Y287051D01*
G01X152442Y287027D02*
X152467Y286953D01*
G01X152392Y286830D02*
X152317Y286928D01*
G01X177966Y246050D02*
X178356Y245659D01*
G01X167966Y246050D02*
X168356Y245659D01*
G01X157966Y246050D02*
X158356Y245659D01*
G01X147966Y246050D02*
X148356Y245659D01*
G01X152467Y286953D02*
X152518Y286904D01*
G01X152769Y286534D02*
X152945Y286387D01*
G01X152744D02*
X152568Y286534D01*
G01X152493Y286756D02*
X152392Y286830D01*
G01X152518Y286904D02*
X152593Y286879D01*
G01X152568Y286731D02*
X152493Y286756D01*
G01X138906Y294409D02*
X190306D01*
G01X147451Y287909D02*
X178312D01*
G01X180856D02*
X178356D01*
G01X151764Y287642D02*
X152945D01*
G01X152292Y287494D02*
X151764D01*
G01X152819D02*
X152442D01*
G01X152593Y286879D02*
X152668D01*
G01Y286731D02*
X152568D01*
G01Y286534D02*
X152769D01*
G01X151764Y286387D02*
X152744D01*
G01X152945Y286239D02*
X151764D01*
G01X146836Y285909D02*
X182236D01*
G01X146836Y277909D02*
X182236D01*
G01X178356Y275909D02*
X180856D01*
G01X147451D02*
X178312D01*
G01X147451Y267909D02*
X178312D01*
G01X180856D02*
X178356D01*
G01X146836Y265909D02*
X182236D01*
G01X146836Y257909D02*
X182236D01*
G01X178356Y255909D02*
X180856D01*
G01X147451D02*
X178312D01*
G01X138911Y249409D02*
X141106D01*
G01X167966Y246050D02*
X171247D01*
G01X157966D02*
X161247D01*
G01X147966D02*
X151247D01*
G01X181247D02*
X177966D01*
G01X178226Y245789D02*
X180986D01*
G01X168226D02*
X170986D01*
G01X158226D02*
X160986D01*
G01X148226D02*
X150986D01*
G01X178356Y245659D02*
X180856D01*
G01X168356D02*
X170856D01*
G01X158356D02*
X160856D01*
G01X148356D02*
X150856D01*
G01X154508Y309409D02*
G03I-4902J0D01*
G01X155706Y329409D02*
G03I-6100J0D01*
G01X155866D02*
G03I-6260J0D01*
G01X163306Y303409D02*
Y339409D01*
G01Y302909D02*
Y303409D01*
G01X155406Y305409D02*
Y298409D01*
G01X150956Y314359D02*
Y304459D01*
G01X148256D02*
Y314359D01*
G01D02*
X150956D01*
G01X163306Y310909D02*
X193306D01*
G01X138906Y305409D02*
X155406D01*
G01X150956Y304459D02*
X148256D01*
G01X193306Y303409D02*
X163306D01*
G01X193306Y302909D02*
X163306D01*
G01X155406Y298409D02*
X190306D01*
G01X186024Y570866D02*
G03I-6890J0D01*
G01Y1161417D02*
G03I-6890J0D01*
G01X188386Y1328740D02*
G03I-9449J0D01*
G01X188780D02*
G03I-9843J0D01*
G01X194094D02*
G03I-15157J0D01*
G01X194685D02*
G03I-15748J0D01*
G01X197638D02*
G03I-18701J0D01*
G01X186811D02*
G03I-7874J0D01*
G01X187402D02*
G03I-8465J0D01*
G01X187795D02*
G03I-8858J0D01*
G01X180117Y1747834D02*
G03I-18701J0D01*
G01X138778Y1772125D02*
G03Y1785511I0J6693D01*
G01Y1772125D02*
G03Y1785511I0J6693D01*
G01X147873Y1769881D02*
Y1787755D01*
G01X169290Y1747834D02*
G03I-7874J0D01*
G01X169880D02*
G03I-8464J0D01*
G01X170274D02*
G03I-8858J0D01*
G01X170865D02*
G03I-9449J0D01*
G01X171160D02*
G03I-9744J0D01*
G01X171258D02*
G03I-9842J0D01*
G01D02*
G03I-9842J0D01*
G01X176573D02*
G03I-15157J0D01*
G01X177164D02*
G03I-15748J0D01*
G01X137677Y1780079D02*
Y1777559D01*
G01D02*
X140196D01*
G01X140905Y1778819D02*
G03I-1968J0D01*
G01X141881Y1778618D02*
X142209Y1778730D01*
G01X141115Y1779624D02*
X141334Y1779736D01*
G01X142209Y1777501D02*
X142319Y1777557D01*
G01X142428Y1777333D02*
X142209Y1777221D01*
G01X142538Y1778674D02*
X142319Y1778507D01*
G01X141389Y1779456D02*
X141225Y1779345D01*
G01X142592Y1777445D02*
X142428Y1777333D01*
G01X140896Y1779401D02*
X141115Y1779624D01*
G01X142209Y1778730D02*
X142319Y1778842D01*
G01Y1777557D02*
X142428Y1777668D01*
G01X141225Y1779345D02*
X141115Y1779177D01*
G01X142647Y1778842D02*
X142538Y1778674D01*
G01X142702Y1777613D02*
X142592Y1777445D01*
G01X142319Y1778842D02*
X142428Y1779065D01*
G01Y1777668D02*
X142483Y1777780D01*
G01X142756D02*
X142702Y1777613D01*
G01X140842Y1779177D02*
X140896Y1779401D01*
G01X142702Y1779065D02*
X142647Y1778842D01*
G01X140196Y1777559D02*
Y1780079D01*
G01X141662Y1778395D02*
Y1778618D01*
G01X142428Y1779065D02*
Y1779177D01*
G01X142483Y1777780D02*
Y1778004D01*
G01X142702Y1779177D02*
Y1779065D01*
G01X142756Y1778004D02*
Y1777780D01*
G01X142702Y1778227D02*
X142756Y1778004D01*
G01X142647Y1779401D02*
X142702Y1779177D01*
G01X140842Y1777613D02*
X140787Y1777780D01*
G01X141061D02*
X141115Y1777668D01*
G01X142483Y1778004D02*
X142374Y1778227D01*
G01X140951Y1777445D02*
X140842Y1777613D01*
G01X142592Y1778395D02*
X142702Y1778227D01*
G01X142428Y1779177D02*
X142319Y1779345D01*
G01X141115Y1777668D02*
X141225Y1777557D01*
G01X142428Y1779624D02*
X142647Y1779401D01*
G01X141334Y1777221D02*
X141115Y1777333D01*
G01X141225Y1777557D02*
X141334Y1777501D01*
G01X142209Y1779736D02*
X142428Y1779624D01*
G01X141115Y1777333D02*
X140951Y1777445D01*
G01X142374Y1778227D02*
X142209Y1778339D01*
G01X142319Y1779345D02*
X142155Y1779456D01*
G01X142209Y1777221D02*
X141991Y1777166D01*
G01X141936Y1777445D02*
X142209Y1777501D01*
G01X141662Y1779512D02*
X141389Y1779456D01*
G01X141334Y1779736D02*
X141717Y1779792D01*
G01X141991Y1777166D02*
X141553D01*
G01X141608Y1777445D02*
X141936D01*
G01X140787Y1777780D02*
X141061D01*
G01X141881Y1778395D02*
X141662D01*
G01Y1778618D02*
X141881D01*
G01X141115Y1779177D02*
X140842D01*
G01X141881Y1779512D02*
X141662D01*
G01X141717Y1779792D02*
X141826D01*
G01D02*
X142209Y1779736D01*
G01Y1778339D02*
X141881Y1778395D01*
G01X141334Y1777501D02*
X141608Y1777445D01*
G01X142155Y1779456D02*
X141881Y1779512D01*
G01X141553Y1777166D02*
X141334Y1777221D01*
G01X142319Y1778507D02*
X142592Y1778395D01*
G01X143937Y1775394D02*
Y1782244D01*
G01X143027Y1773819D02*
X143937Y1775394D01*
G01X180117Y1823031D02*
G03I-18701J0D01*
G01X169290D02*
G03I-7874J0D01*
G01X169880D02*
G03I-8464J0D01*
G01X170274D02*
G03I-8858J0D01*
G01X170865D02*
G03I-9449J0D01*
G01X171160D02*
G03I-9744J0D01*
G01X171258D02*
G03I-9842J0D01*
G01D02*
G03I-9842J0D01*
G01X176573D02*
G03I-15157J0D01*
G01X177164D02*
G03I-15748J0D01*
G01X140196Y1780079D02*
X137677D01*
G01X143937Y1782244D02*
X143027Y1783819D01*
G01X187008Y1889764D02*
G03I-7874J0D01*
G01X168110Y1929134D02*
G03Y1937008I0J3937D01*
G01Y1929134D02*
G03Y1937008I0J3937D01*
G01X340559Y1968504D02*
X142520D01*
G01X340559D02*
X142520D01*
G01X177064Y1967104D02*
Y1969904D01*
G01X145569Y1967104D02*
Y1969904D01*
G01X243445Y-80235D02*
Y-68873D01*
X238190Y-77016D01*
X245292D01*
G01X202756Y39370D02*
G03X206693Y43307I0J3937D01*
G01X202756Y39370D02*
G03X206693Y43307I0J3937D01*
G01X202756Y39370D02*
G03X206693Y43307I0J3937D01*
G01X202756Y39370D02*
G03X206693Y43307I0J3937D01*
G01X202756Y39370D02*
G03X206693Y43307I0J3937D01*
G01X202756Y39370D02*
G03X206693Y43307I0J3937D01*
G01X218504Y39370D02*
X348425D01*
G01X214567Y43307D02*
G03X218504Y39370I3937J0D01*
G01X222441Y31496D02*
X198819D01*
G01X222441D02*
G03Y39370I0J3937D01*
G01X198819D02*
G03Y31496I0J-3937D01*
G01X202756Y39370D02*
G03X206693Y43307I0J3937D01*
G01X218504Y39370D02*
X348425D01*
G01X214567Y43307D02*
G03X218504Y39370I3937J0D01*
G01X222441Y31496D02*
X198819D01*
G01X222441D02*
G03Y39370I0J3937D01*
G01X198819D02*
G03Y31496I0J-3937D01*
G01X206693Y1925197D02*
Y43307D01*
G01Y1925197D02*
Y43307D01*
G01Y1925197D02*
Y43307D01*
G01X214567Y161417D02*
Y43307D01*
G01X206693Y1925197D02*
Y43307D01*
G01Y1925197D02*
Y43307D01*
G01X193306Y137909D02*
Y310909D01*
G01X190306Y298409D02*
Y150409D01*
G01X188306Y154409D02*
Y199409D01*
G01X206693Y161417D02*
Y1807087D01*
G01X214567D02*
Y161417D01*
G01Y169291D02*
G03X206693I-3937J0D01*
G01Y161417D02*
Y1807087D01*
G01X214567D02*
Y161417D01*
G01Y169291D02*
G03X206693I-3937J0D01*
G01X188106Y199409D02*
Y249409D01*
G01Y199409D02*
X190302D01*
G01X206693Y200000D02*
G03X214567I3937J0D01*
G01X206693D02*
G03X214567I3937J0D01*
G01X188306Y249409D02*
Y294409D01*
G01X188106Y249409D02*
X190302D01*
G01X214567Y436220D02*
G03X206693I-3937J0D01*
G01X214567D02*
G03X206693I-3937J0D01*
G01Y466929D02*
G03X214567I3937J0D01*
G01X206693D02*
G03X214567I3937J0D01*
G01Y703149D02*
G03X206693I-3937J0D01*
G01X214567D02*
G03X206693I-3937J0D01*
G01Y733858D02*
G03X214567I3937J0D01*
G01X206693D02*
G03X214567I3937J0D01*
G01Y970867D02*
G03X206693I-3937J0D01*
G01Y997637D02*
G03X214567I3937J0D01*
G01Y970867D02*
G03X206693I-3937J0D01*
G01Y997637D02*
G03X214567I3937J0D01*
G01X206693Y1265355D02*
G03X214567I3937J0D01*
G01Y1234646D02*
G03X206693I-3937J0D01*
G01Y1265355D02*
G03X214567I3937J0D01*
G01Y1234646D02*
G03X206693I-3937J0D01*
G01X214567Y1501575D02*
G03X206693I-3937J0D01*
G01X214567D02*
G03X206693I-3937J0D01*
G01Y1532284D02*
G03X214567I3937J0D01*
G01X206693D02*
G03X214567I3937J0D01*
G01X188384Y1856889D02*
Y1689960D01*
G01Y1856889D02*
Y1689960D01*
G01X214567Y1768504D02*
G03X206693I-3937J0D01*
G01X214567D02*
G03X206693I-3937J0D01*
G01X214567Y1807087D02*
Y1925197D01*
G01X206693Y1799213D02*
G03X214567I3937J0D01*
G01X206693D02*
G03X214567I3937J0D01*
G01X206693Y1925197D02*
G03X202756Y1929134I-3937J0D01*
G01X206693Y1925443D02*
Y1974916D01*
G01X214567Y1925443D02*
Y1975042D01*
G01X206693Y1925197D02*
G03X202756Y1929134I-3937J0D01*
G01X206693Y1925197D02*
G03X202756Y1929134I-3937J0D01*
G01X206693Y1925197D02*
G03X202756Y1929134I-3937J0D01*
G01X206693Y1925197D02*
G03X202756Y1929134I-3937J0D01*
G01X206693Y1925197D02*
G03X202756Y1929134I-3937J0D01*
G01X218504D02*
G03X214567Y1925197I0J-3937D01*
G01X348425Y1929134D02*
X218504D01*
G01X198819Y1937008D02*
G03Y1929134I0J-3937D01*
G01X222441D02*
G03Y1937008I0J3937D01*
G01X206693Y1925197D02*
G03X202756Y1929134I-3937J0D01*
G01X218504D02*
G03X214567Y1925197I0J-3937D01*
G01X348425Y1929134D02*
X218504D01*
G01X198819Y1937008D02*
G03Y1929134I0J-3937D01*
G01X222441D02*
G03Y1937008I0J3937D01*
G01X206693Y1974916D02*
X205074Y1990664D01*
G01X214567Y1975042D02*
X218027Y1990790D01*
G01X198819Y1937008D02*
X222441D01*
G01X198819D02*
X222441D01*
G01X208559Y1967104D02*
Y1969904D01*
G01X221964Y2009733D02*
X214389D01*
X215904Y2008597D01*
G01X221964D02*
Y2010870D01*
G01Y2017308D02*
X214389D01*
X215904Y2016172D01*
G01X221964D02*
Y2018445D01*
G01X218808Y2023084D02*
X217924Y2023747D01*
X217419Y2024315D01*
X217167Y2025073D01*
X217419Y2025736D01*
X217924Y2026209D01*
X218682Y2026588D01*
X219565Y2026683D01*
X220323Y2026588D01*
X221080Y2026209D01*
X221712Y2025641D01*
X221964Y2024978D01*
X221712Y2024221D01*
X220954Y2023558D01*
X219818Y2023179D01*
X218555Y2023084D01*
X216914Y2023274D01*
X216030Y2023558D01*
X215147Y2024031D01*
X214515Y2024694D01*
X214389Y2025357D01*
X214641Y2026020D01*
X215273Y2026493D01*
G01X222216Y2032458D02*
X222090Y2032269D01*
X221838D01*
X221712Y2032458D01*
X221838Y2032648D01*
X222090D01*
X222216Y2032458D01*
G01X214389Y2040033D02*
X214641Y2039276D01*
X215273Y2038708D01*
X216030Y2038329D01*
X217040Y2038045D01*
X218177Y2037950D01*
X219313Y2038045D01*
X220323Y2038329D01*
X221080Y2038708D01*
X221712Y2039276D01*
X221964Y2040033D01*
X221712Y2040791D01*
X221080Y2041359D01*
X220323Y2041738D01*
X219313Y2042022D01*
X218177Y2042117D01*
X217040Y2042022D01*
X216030Y2041738D01*
X215273Y2041359D01*
X214641Y2040791D01*
X214389Y2040033D01*
G01Y2047608D02*
X214641Y2046851D01*
X215273Y2046283D01*
X216030Y2045904D01*
X217040Y2045620D01*
X218177Y2045525D01*
X219313Y2045620D01*
X220323Y2045904D01*
X221080Y2046283D01*
X221712Y2046851D01*
X221964Y2047608D01*
X221712Y2048366D01*
X221080Y2048934D01*
X220323Y2049313D01*
X219313Y2049597D01*
X218177Y2049692D01*
X217040Y2049597D01*
X216030Y2049313D01*
X215273Y2048934D01*
X214641Y2048366D01*
X214389Y2047608D01*
G01X209011Y2009606D02*
X201436D01*
X202951Y2008470D01*
G01X209011D02*
Y2010743D01*
G01Y2017181D02*
X201436D01*
X202951Y2016045D01*
G01X209011D02*
Y2018318D01*
G01Y2025893D02*
X201436D01*
X206865Y2022389D01*
Y2027124D01*
G01X209263Y2032331D02*
X209137Y2032142D01*
X208885D01*
X208759Y2032331D01*
X208885Y2032521D01*
X209137D01*
X209263Y2032331D01*
G01X201436Y2039906D02*
X201688Y2039149D01*
X202320Y2038581D01*
X203077Y2038202D01*
X204087Y2037918D01*
X205224Y2037823D01*
X206360Y2037918D01*
X207370Y2038202D01*
X208127Y2038581D01*
X208759Y2039149D01*
X209011Y2039906D01*
X208759Y2040664D01*
X208127Y2041232D01*
X207370Y2041611D01*
X206360Y2041895D01*
X205224Y2041990D01*
X204087Y2041895D01*
X203077Y2041611D01*
X202320Y2041232D01*
X201688Y2040664D01*
X201436Y2039906D01*
G01Y2047481D02*
X201688Y2046724D01*
X202320Y2046156D01*
X203077Y2045777D01*
X204087Y2045493D01*
X205224Y2045398D01*
X206360Y2045493D01*
X207370Y2045777D01*
X208127Y2046156D01*
X208759Y2046724D01*
X209011Y2047481D01*
X208759Y2048239D01*
X208127Y2048807D01*
X207370Y2049186D01*
X206360Y2049470D01*
X205224Y2049565D01*
X204087Y2049470D01*
X203077Y2049186D01*
X202320Y2048807D01*
X201688Y2048239D01*
X201436Y2047481D01*
G01X205074Y1990664D02*
Y2006412D01*
G01X218027Y1990790D02*
Y2006538D01*
G01X243445Y2097521D02*
Y2108883D01*
X238190Y2100740D01*
X245292D01*
G01X253150Y31496D02*
X344488D01*
G01X253150Y39370D02*
G03Y31496I0J-3937D01*
G01D02*
X344488D01*
G01X253150Y39370D02*
G03Y31496I0J-3937D01*
G01Y1937008D02*
G03Y1929134I0J-3937D01*
G01Y1937008D02*
G03Y1929134I0J-3937D01*
G01Y1937008D02*
X344496D01*
G01X253150D02*
X344496D01*
G01X271549Y1967104D02*
Y1969904D01*
G01X240054Y1967104D02*
Y1969904D01*
G01X331685Y-65085D02*
X1513280D01*
G01X340551Y0D02*
G03X344488Y3937I0J3937D01*
G01X340551Y0D02*
G03X344488Y3937I0J3937D01*
G01X310688Y936637D02*
Y986637D01*
G01X325062Y936637D02*
X296312D01*
G01X344496Y1964567D02*
G03X340559Y1968504I-3937J0D01*
G01X344496Y1964567D02*
G03X340559Y1968504I-3937J0D01*
G01X303044Y1967104D02*
Y1969904D01*
G01X351102Y-65085D02*
Y-84022D01*
G01X356299Y0D02*
X417323D01*
G01X352362Y3937D02*
G03X356299Y0I3937J0D01*
G01X352362Y35433D02*
Y3937D01*
G01Y35433D02*
G03X348425Y39370I-3937J0D01*
G01X344488Y7874D02*
Y3937D01*
G01D02*
Y7874D01*
G01X352362D02*
G03X344488I-3937J0D01*
G01Y31496D02*
G03X352362I3937J0D01*
G01X356299Y0D02*
X417323D01*
G01X352362Y3937D02*
G03X356299Y0I3937J0D01*
G01X352362Y35433D02*
Y3937D01*
G01Y35433D02*
G03X348425Y39370I-3937J0D01*
G01X344488Y7874D02*
Y3937D01*
G01D02*
Y7874D01*
G01X352362D02*
G03X344488I-3937J0D01*
G01Y31496D02*
G03X352362I3937J0D01*
G01X348425Y1929134D02*
G03X352362Y1933071I0J3937D01*
G01Y1964567D02*
Y1933071D01*
G01X348425Y1929134D02*
G03X352362Y1933071I0J3937D01*
G01Y1964567D02*
Y1933071D01*
G01X356299Y1968504D02*
G03X352362Y1964567I0J-3937D01*
G01X417323Y1968504D02*
X356299D01*
G01X344496Y1960889D02*
Y1964567D01*
G01Y1960889D02*
G03X352370I3937J0D01*
G01Y1937008D02*
G03X344496I-3937J0D01*
G01X356299Y1968504D02*
G03X352362Y1964567I0J-3937D01*
G01X417323Y1968504D02*
X356299D01*
G01X344496Y1960889D02*
Y1964567D01*
G01Y1960889D02*
G03X352370I3937J0D01*
G01Y1937008D02*
G03X344496I-3937J0D01*
G01X351102Y2112671D02*
Y2093734D01*
G01X429134Y3937D02*
G03X433071Y0I3937J0D01*
G01X429134Y1964567D02*
Y3937D01*
G01X433071Y0D02*
X494095D01*
G01X421260Y3937D02*
Y1964567D01*
G01X417323Y0D02*
G03X421260Y3937I0J3937D01*
G01X429134Y11811D02*
G03X421260I-3937J0D01*
G01Y42520D02*
G03X429134I3937J0D01*
G01Y3937D02*
G03X433071Y0I3937J0D01*
G01X429134Y1964567D02*
Y3937D01*
G01X433071Y0D02*
X494095D01*
G01X421260Y3937D02*
Y1964567D01*
G01X417323Y0D02*
G03X421260Y3937I0J3937D01*
G01X429134Y11811D02*
G03X421260I-3937J0D01*
G01Y42520D02*
G03X429134I3937J0D01*
G01Y278740D02*
G03X421260I-3937J0D01*
G01X429134D02*
G03X421260I-3937J0D01*
G01Y309449D02*
G03X429134I3937J0D01*
G01X421260D02*
G03X429134I3937J0D01*
G01Y545669D02*
G03X421260I-3937J0D01*
G01X429134D02*
G03X421260I-3937J0D01*
G01Y576378D02*
G03X429134I3937J0D01*
G01X421260D02*
G03X429134I3937J0D01*
G01X421260Y862205D02*
G03X429134I3937J0D01*
G01Y831496D02*
G03X421260I-3937J0D01*
G01Y862205D02*
G03X429134I3937J0D01*
G01Y831496D02*
G03X421260I-3937J0D01*
G01X429134Y1106299D02*
G03X421260I-3937J0D01*
G01X429134D02*
G03X421260I-3937J0D01*
G01Y1137008D02*
G03X429134I3937J0D01*
G01X421260D02*
G03X429134I3937J0D01*
G01X421260Y1422835D02*
G03X429134I3937J0D01*
G01Y1392126D02*
G03X421260I-3937J0D01*
G01Y1422835D02*
G03X429134I3937J0D01*
G01Y1392126D02*
G03X421260I-3937J0D01*
G01X429134Y1659055D02*
G03X421260I-3937J0D01*
G01X429134D02*
G03X421260I-3937J0D01*
G01Y1689764D02*
G03X429134I3937J0D01*
G01X421260D02*
G03X429134I3937J0D01*
G01Y1925984D02*
G03X421260I-3937J0D01*
G01X429134D02*
G03X421260I-3937J0D01*
G01Y1978687D02*
X415810Y1994435D01*
G01X421260Y1956939D02*
Y1978687D01*
G01X429134Y1981957D02*
X432943Y1997705D01*
G01X429134Y1960027D02*
Y1981957D01*
G01X433071Y1968504D02*
G03X429134Y1964567I0J-3937D01*
G01X494095Y1968504D02*
X433071D01*
G01X421260Y1964567D02*
G03X417323Y1968504I-3937J0D01*
G01X421260Y1956693D02*
G03X429134I3937J0D01*
G01X433071Y1968504D02*
G03X429134Y1964567I0J-3937D01*
G01X494095Y1968504D02*
X433071D01*
G01X421260Y1964567D02*
G03X417323Y1968504I-3937J0D01*
G01X421260Y1956693D02*
G03X429134I3937J0D01*
G01X433071Y1968504D02*
G03X429134Y1964567I0J-3937D01*
G01X421260D02*
G03X417323Y1968504I-3937J0D01*
G01X436880Y2016648D02*
X429305D01*
X430820Y2015512D01*
G01X436880D02*
Y2017785D01*
G01Y2024034D02*
X435239Y2024223D01*
X433850Y2024508D01*
X432587Y2024886D01*
X431199Y2025360D01*
X429305Y2026117D01*
Y2022330D01*
G01Y2031798D02*
X429557Y2031041D01*
X430189Y2030473D01*
X430946Y2030094D01*
X431956Y2029810D01*
X433093Y2029715D01*
X434229Y2029810D01*
X435239Y2030094D01*
X435996Y2030473D01*
X436628Y2031041D01*
X436880Y2031798D01*
X436628Y2032556D01*
X435996Y2033124D01*
X435239Y2033503D01*
X434229Y2033787D01*
X433093Y2033882D01*
X431956Y2033787D01*
X430946Y2033503D01*
X430189Y2033124D01*
X429557Y2032556D01*
X429305Y2031798D01*
G01X437132Y2039373D02*
X437006Y2039184D01*
X436754D01*
X436628Y2039373D01*
X436754Y2039563D01*
X437006D01*
X437132Y2039373D01*
G01X435744Y2044865D02*
X436375Y2045433D01*
X436754Y2046096D01*
X436880Y2046948D01*
X436628Y2047801D01*
X436123Y2048463D01*
X435239Y2048937D01*
X434229Y2049032D01*
X433219Y2048842D01*
X432587Y2048369D01*
X432083Y2047706D01*
X431956Y2047043D01*
X432083Y2046380D01*
X432587Y2045528D01*
X429305Y2045812D01*
Y2048369D01*
G01Y2054523D02*
X429557Y2053766D01*
X430189Y2053198D01*
X430946Y2052819D01*
X431956Y2052535D01*
X433093Y2052440D01*
X434229Y2052535D01*
X435239Y2052819D01*
X435996Y2053198D01*
X436628Y2053766D01*
X436880Y2054523D01*
X436628Y2055281D01*
X435996Y2055849D01*
X435239Y2056228D01*
X434229Y2056512D01*
X433093Y2056607D01*
X431956Y2056512D01*
X430946Y2056228D01*
X430189Y2055849D01*
X429557Y2055281D01*
X429305Y2054523D01*
G01X419747Y2013377D02*
X412172D01*
X413687Y2012241D01*
G01X419747D02*
Y2014514D01*
G01X416591Y2019153D02*
X415707Y2019816D01*
X415202Y2020384D01*
X414950Y2021142D01*
X415202Y2021805D01*
X415707Y2022278D01*
X416465Y2022657D01*
X417348Y2022752D01*
X418106Y2022657D01*
X418863Y2022278D01*
X419495Y2021710D01*
X419747Y2021047D01*
X419495Y2020290D01*
X418737Y2019627D01*
X417601Y2019248D01*
X416338Y2019153D01*
X414697Y2019343D01*
X413813Y2019627D01*
X412930Y2020100D01*
X412298Y2020763D01*
X412172Y2021426D01*
X412424Y2022089D01*
X413056Y2022562D01*
G01X419747Y2028527D02*
X419621Y2029190D01*
X419242Y2029948D01*
X418611Y2030421D01*
X417727Y2030611D01*
X416843Y2030421D01*
X416086Y2029853D01*
X415707Y2029001D01*
Y2028054D01*
X415454Y2027486D01*
X414823Y2027012D01*
X413940Y2026823D01*
X413056Y2027107D01*
X412424Y2027770D01*
X412172Y2028527D01*
X412424Y2029285D01*
X413056Y2029948D01*
X413940Y2030232D01*
X414823Y2030042D01*
X415454Y2029569D01*
X415707Y2029001D01*
Y2028054D01*
X416086Y2027202D01*
X416843Y2026634D01*
X417727Y2026444D01*
X418611Y2026634D01*
X419242Y2027107D01*
X419621Y2027865D01*
X419747Y2028527D01*
G01X419999Y2036102D02*
X419873Y2035913D01*
X419621D01*
X419495Y2036102D01*
X419621Y2036292D01*
X419873D01*
X419999Y2036102D01*
G01X418611Y2041594D02*
X419242Y2042162D01*
X419621Y2042825D01*
X419747Y2043677D01*
X419495Y2044530D01*
X418990Y2045192D01*
X418106Y2045666D01*
X417096Y2045761D01*
X416086Y2045571D01*
X415454Y2045098D01*
X414950Y2044435D01*
X414823Y2043772D01*
X414950Y2043109D01*
X415454Y2042257D01*
X412172Y2042541D01*
Y2045098D01*
G01Y2051252D02*
X412424Y2050495D01*
X413056Y2049927D01*
X413813Y2049548D01*
X414823Y2049264D01*
X415960Y2049169D01*
X417096Y2049264D01*
X418106Y2049548D01*
X418863Y2049927D01*
X419495Y2050495D01*
X419747Y2051252D01*
X419495Y2052010D01*
X418863Y2052578D01*
X418106Y2052957D01*
X417096Y2053241D01*
X415960Y2053336D01*
X414823Y2053241D01*
X413813Y2052957D01*
X413056Y2052578D01*
X412424Y2052010D01*
X412172Y2051252D01*
G01X415810Y1994435D02*
Y2010183D01*
G01X432943Y1997705D02*
Y2013453D01*
G01X458286Y-78531D02*
X459138Y-79478D01*
X460133Y-80046D01*
X461411Y-80235D01*
X462689Y-79856D01*
X463683Y-79099D01*
X464394Y-77773D01*
X464536Y-76258D01*
X464252Y-74743D01*
X463541Y-73797D01*
X462547Y-73039D01*
X461553Y-72850D01*
X460559Y-73039D01*
X459281Y-73797D01*
X459707Y-68873D01*
X463541D01*
G01X494095Y0D02*
G03X498032Y3937I0J3937D01*
G01X494095Y0D02*
G03X498032Y3937I0J3937D01*
G01Y1964567D02*
G03X494095Y1968504I-3937J0D01*
G01X498032Y1964567D02*
G03X494095Y1968504I-3937J0D01*
G01X458286Y2099225D02*
X459138Y2098278D01*
X460133Y2097710D01*
X461411Y2097521D01*
X462689Y2097900D01*
X463683Y2098657D01*
X464394Y2099983D01*
X464536Y2101498D01*
X464252Y2103013D01*
X463541Y2103959D01*
X462547Y2104717D01*
X461553Y2104906D01*
X460559Y2104717D01*
X459281Y2103959D01*
X459707Y2108883D01*
X463541D01*
G01X505897Y0D02*
X648386D01*
G01X501969Y39370D02*
X631890D01*
G01X501969D02*
G03X498032Y35433I0J-3937D01*
G01Y3937D02*
Y35433D01*
G01X505897Y7615D02*
Y0D01*
G01X597244Y31496D02*
X505897D01*
G01Y7615D02*
G03X498023I-3937J0D01*
G01Y31496D02*
G03X505897I3937J0D01*
G01X501969Y39370D02*
X631890D01*
G01X501969D02*
G03X498032Y35433I0J-3937D01*
G01Y3937D02*
Y35433D01*
G01X505897Y7615D02*
Y0D01*
G01X597244Y31496D02*
X505897D01*
G01Y7615D02*
G03X498023I-3937J0D01*
G01Y31496D02*
G03X505897I3937J0D01*
G01X552221Y1001686D02*
Y951686D01*
G01X537847Y1001686D02*
X566597D01*
G01X498032Y1933071D02*
Y1960630D01*
G01Y1933071D02*
G03X501969Y1929134I3937J0D01*
G01X631890D02*
X501969D01*
G01X498032Y1933071D02*
Y1964567D01*
G01Y1933071D02*
G03X501969Y1929134I3937J0D01*
G01X631890D02*
X501969D01*
G01X505906Y1968504D02*
X648386D01*
G01X505906Y1960630D02*
Y1968504D01*
G01X597244Y1937008D02*
X505906D01*
G01X498032Y1960630D02*
G03X505906I3937J0D01*
G01Y1937008D02*
G03X498032I-3937J0D01*
G01X505906Y1960630D02*
Y1968504D01*
G01X597244Y1937008D02*
X505906D01*
G01X498032Y1960630D02*
G03X505906I3937J0D01*
G01Y1937008D02*
G03X498032I-3937J0D01*
G01X570772Y-65085D02*
Y-84022D01*
G01X593704Y29248D02*
X609704D01*
G01X593704Y13248D02*
X609704D01*
G01X593704Y29248D02*
Y13248D01*
G01X610399Y1940497D02*
X594399D01*
G01Y1956497D02*
Y1940497D01*
G01X610399Y1956497D02*
X594399D01*
G01X570772Y2112671D02*
Y2093734D01*
G01X643701Y169256D02*
Y39370D01*
G01X650689Y19685D02*
G03I-6988J0D01*
G01D02*
G03I-6988J0D01*
G01X635827Y31496D02*
G03X643701Y39370I0J7874D01*
G01X635827Y31496D02*
X627953D01*
G01X635827D02*
X627953D01*
G01X631890Y39370D02*
G03X635827Y43307I0J3937D01*
G01X597244Y31496D02*
G03Y39370I0J3937D01*
G01X627953D02*
G03Y31496I0J-3937D01*
G01X631890Y39370D02*
G03X635827Y43307I0J3937D01*
G01X597244Y31496D02*
G03Y39370I0J3937D01*
G01X627953D02*
G03Y31496I0J-3937D01*
G01X609704Y13248D02*
Y29248D01*
G01X599204Y18748D02*
X604204D01*
G01Y23748D02*
X599204D01*
G01Y18748D02*
Y23748D01*
G01X604204D02*
Y18748D01*
G01X601704D02*
Y23748D01*
G01X599204Y21248D02*
X604204D01*
G01X635827Y161417D02*
Y43307D01*
G01X643701Y169256D02*
G03X635827I-3937J0D01*
G01X643701D02*
G03X635827I-3937J0D01*
G01Y161417D02*
Y1925197D01*
G01Y161417D02*
Y1807087D01*
G01X643701Y436186D02*
Y199965D01*
G01X635827D02*
G03X643701I3937J0D01*
G01X635827D02*
G03X643701I3937J0D01*
G01Y436186D02*
G03X635827I-3937J0D01*
G01X643701D02*
G03X635827I-3937J0D01*
G01X643701Y703115D02*
Y466894D01*
G01X635827D02*
G03X643701I3937J0D01*
G01X635827D02*
G03X643701I3937J0D01*
G01Y703115D02*
G03X635827I-3937J0D01*
G01X643701D02*
G03X635827I-3937J0D01*
G01X643701Y970832D02*
Y733823D01*
G01X635827D02*
G03X643701I3937J0D01*
G01X635827D02*
G03X643701I3937J0D01*
G01Y1234611D02*
Y997603D01*
G01X635827D02*
G03X643701I3937J0D01*
G01Y970832D02*
G03X635827I-3937J0D01*
G01Y997603D02*
G03X643701I3937J0D01*
G01Y970832D02*
G03X635827I-3937J0D01*
G01X643701Y1501541D02*
Y1265320D01*
G01X635827D02*
G03X643701I3937J0D01*
G01Y1234611D02*
G03X635827I-3937J0D01*
G01Y1265320D02*
G03X643701I3937J0D01*
G01Y1234611D02*
G03X635827I-3937J0D01*
G01X643701Y1501541D02*
G03X635827I-3937J0D01*
G01X643701D02*
G03X635827I-3937J0D01*
G01X643701Y1768470D02*
Y1532249D01*
G01X635827D02*
G03X643701I3937J0D01*
G01X635827D02*
G03X643701I3937J0D01*
G01Y1768470D02*
G03X635827I-3937J0D01*
G01X643701D02*
G03X635827I-3937J0D01*
G01Y1799178D02*
G03X643701I3937J0D01*
G01X635827D02*
G03X643701I3937J0D01*
G01Y1929134D02*
Y1799178D01*
G01X635827Y1915647D02*
Y1974929D01*
G01X643701Y1929134D02*
G03X635827Y1937008I-7874J0D01*
G01Y1925197D02*
G03X631890Y1929134I-3937J0D01*
G01X627953Y1937008D02*
G03Y1929134I0J-3937D01*
G01X597244D02*
G03Y1937008I0J3937D01*
G01X635827Y1925197D02*
G03X631890Y1929134I-3937J0D01*
G01X627953Y1937008D02*
G03Y1929134I0J-3937D01*
G01X597244D02*
G03Y1937008I0J3937D01*
G01X635827Y1974929D02*
X634615Y1990677D01*
G01X650689Y1948819D02*
G03I-6988J0D01*
G01D02*
G03I-6988J0D01*
G01D02*
G03I-6988J0D01*
G01X627953Y1937008D02*
X635827D01*
G01X627953D02*
X635827D01*
G01X610399Y1940497D02*
Y1956497D01*
G01X604899Y1950997D02*
X599899D01*
G01Y1945997D02*
X604899D01*
G01Y1950997D02*
Y1945997D01*
G01X599899D02*
Y1950997D01*
G01X602399D02*
Y1945997D01*
G01X604899Y1948497D02*
X599899D01*
G01X632239Y2007820D02*
X631482Y2008389D01*
X631103Y2009051D01*
X630977Y2009809D01*
X631229Y2010756D01*
X631861Y2011419D01*
X632618Y2011608D01*
X633376Y2011513D01*
X634007Y2011134D01*
X635270Y2009241D01*
X636153Y2008389D01*
X637416Y2007820D01*
X638552Y2007631D01*
Y2011608D01*
G01X632239Y2015395D02*
X631482Y2015964D01*
X631103Y2016626D01*
X630977Y2017384D01*
X631229Y2018331D01*
X631861Y2018994D01*
X632618Y2019183D01*
X633376Y2019088D01*
X634007Y2018709D01*
X635270Y2016816D01*
X636153Y2015964D01*
X637416Y2015395D01*
X638552Y2015206D01*
Y2019183D01*
G01X637037Y2022686D02*
X637921Y2023254D01*
X638426Y2024012D01*
X638552Y2024864D01*
X638426Y2025622D01*
X637795Y2026379D01*
X637037Y2026853D01*
X636280Y2026947D01*
X635396Y2026758D01*
X634765Y2026095D01*
X634512Y2025432D01*
Y2024580D01*
G01Y2025432D02*
X634133Y2026000D01*
X633502Y2026474D01*
X632745Y2026663D01*
X631987Y2026474D01*
X631356Y2026000D01*
X630977Y2025148D01*
X631103Y2024296D01*
X631608Y2023444D01*
G01X638804Y2032344D02*
X638678Y2032155D01*
X638426D01*
X638300Y2032344D01*
X638426Y2032534D01*
X638678D01*
X638804Y2032344D01*
G01X630977Y2039919D02*
X631229Y2039162D01*
X631861Y2038594D01*
X632618Y2038215D01*
X633628Y2037931D01*
X634765Y2037836D01*
X635901Y2037931D01*
X636911Y2038215D01*
X637668Y2038594D01*
X638300Y2039162D01*
X638552Y2039919D01*
X638300Y2040677D01*
X637668Y2041245D01*
X636911Y2041624D01*
X635901Y2041908D01*
X634765Y2042003D01*
X633628Y2041908D01*
X632618Y2041624D01*
X631861Y2041245D01*
X631229Y2040677D01*
X630977Y2039919D01*
G01Y2047494D02*
X631229Y2046737D01*
X631861Y2046169D01*
X632618Y2045790D01*
X633628Y2045506D01*
X634765Y2045411D01*
X635901Y2045506D01*
X636911Y2045790D01*
X637668Y2046169D01*
X638300Y2046737D01*
X638552Y2047494D01*
X638300Y2048252D01*
X637668Y2048820D01*
X636911Y2049199D01*
X635901Y2049483D01*
X634765Y2049578D01*
X633628Y2049483D01*
X632618Y2049199D01*
X631861Y2048820D01*
X631229Y2048252D01*
X630977Y2047494D01*
G01X634615Y1990677D02*
Y2006425D01*
G01X678381Y-75501D02*
X679376Y-74175D01*
X680228Y-73418D01*
X681364Y-73039D01*
X682358Y-73418D01*
X683068Y-74175D01*
X683637Y-75311D01*
X683779Y-76637D01*
X683637Y-77773D01*
X683068Y-78910D01*
X682216Y-79856D01*
X681222Y-80235D01*
X680086Y-79856D01*
X679092Y-78720D01*
X678523Y-77016D01*
X678381Y-75122D01*
X678665Y-72661D01*
X679092Y-71335D01*
X679802Y-70009D01*
X680796Y-69062D01*
X681790Y-68873D01*
X682784Y-69252D01*
X683495Y-70199D01*
G01X648386Y0D02*
G03X663386Y15000I0J15000D01*
G01Y1953504D02*
Y15000D01*
G01Y1902405D02*
Y1977587D01*
G01D02*
X663848Y1993335D01*
G01X663386Y1953504D02*
G03X648386Y1968504I-15000J0D01*
G01X661472Y2010478D02*
X660715Y2011047D01*
X660336Y2011709D01*
X660210Y2012467D01*
X660462Y2013414D01*
X661094Y2014077D01*
X661851Y2014266D01*
X662609Y2014171D01*
X663240Y2013792D01*
X664503Y2011899D01*
X665386Y2011047D01*
X666649Y2010478D01*
X667785Y2010289D01*
Y2014266D01*
G01X666270Y2017769D02*
X667154Y2018337D01*
X667659Y2019095D01*
X667785Y2019947D01*
X667659Y2020705D01*
X667028Y2021462D01*
X666270Y2021936D01*
X665513Y2022030D01*
X664629Y2021841D01*
X663998Y2021178D01*
X663745Y2020515D01*
Y2019663D01*
G01Y2020515D02*
X663366Y2021083D01*
X662735Y2021557D01*
X661978Y2021746D01*
X661220Y2021557D01*
X660589Y2021083D01*
X660210Y2020231D01*
X660336Y2019379D01*
X660841Y2018527D01*
G01X660210Y2027427D02*
X660462Y2026670D01*
X661094Y2026102D01*
X661851Y2025723D01*
X662861Y2025439D01*
X663998Y2025344D01*
X665134Y2025439D01*
X666144Y2025723D01*
X666901Y2026102D01*
X667533Y2026670D01*
X667785Y2027427D01*
X667533Y2028185D01*
X666901Y2028753D01*
X666144Y2029132D01*
X665134Y2029416D01*
X663998Y2029511D01*
X662861Y2029416D01*
X661851Y2029132D01*
X661094Y2028753D01*
X660462Y2028185D01*
X660210Y2027427D01*
G01X668037Y2035002D02*
X667911Y2034813D01*
X667659D01*
X667533Y2035002D01*
X667659Y2035192D01*
X667911D01*
X668037Y2035002D01*
G01X660210Y2042577D02*
X660462Y2041820D01*
X661094Y2041252D01*
X661851Y2040873D01*
X662861Y2040589D01*
X663998Y2040494D01*
X665134Y2040589D01*
X666144Y2040873D01*
X666901Y2041252D01*
X667533Y2041820D01*
X667785Y2042577D01*
X667533Y2043335D01*
X666901Y2043903D01*
X666144Y2044282D01*
X665134Y2044566D01*
X663998Y2044661D01*
X662861Y2044566D01*
X661851Y2044282D01*
X661094Y2043903D01*
X660462Y2043335D01*
X660210Y2042577D01*
G01Y2050152D02*
X660462Y2049395D01*
X661094Y2048827D01*
X661851Y2048448D01*
X662861Y2048164D01*
X663998Y2048069D01*
X665134Y2048164D01*
X666144Y2048448D01*
X666901Y2048827D01*
X667533Y2049395D01*
X667785Y2050152D01*
X667533Y2050910D01*
X666901Y2051478D01*
X666144Y2051857D01*
X665134Y2052141D01*
X663998Y2052236D01*
X662861Y2052141D01*
X661851Y2051857D01*
X661094Y2051478D01*
X660462Y2050910D01*
X660210Y2050152D01*
G01X663848Y1993335D02*
Y2009083D01*
G01X678381Y2102255D02*
X679376Y2103581D01*
X680228Y2104338D01*
X681364Y2104717D01*
X682358Y2104338D01*
X683068Y2103581D01*
X683637Y2102445D01*
X683779Y2101119D01*
X683637Y2099983D01*
X683068Y2098846D01*
X682216Y2097900D01*
X681222Y2097521D01*
X680086Y2097900D01*
X679092Y2099036D01*
X678523Y2100740D01*
X678381Y2102634D01*
X678665Y2105095D01*
X679092Y2106421D01*
X679802Y2107747D01*
X680796Y2108694D01*
X681790Y2108883D01*
X682784Y2108504D01*
X683495Y2107557D01*
G01X790441Y-65085D02*
Y-84022D01*
G01X796412Y2016087D02*
X797062Y2015365D01*
X797820Y2014932D01*
X798794Y2014788D01*
X799768Y2015077D01*
X800526Y2015654D01*
X801068Y2016664D01*
X801176Y2017819D01*
X800959Y2018974D01*
X800418Y2019696D01*
X799660Y2020273D01*
X798902Y2020418D01*
X798144Y2020273D01*
X797170Y2019696D01*
X797495Y2023449D01*
X800418D01*
G01X807455D02*
X806589Y2023160D01*
X805939Y2022439D01*
X805506Y2021573D01*
X805181Y2020418D01*
X805073Y2019118D01*
X805181Y2017819D01*
X805506Y2016664D01*
X805939Y2015798D01*
X806589Y2015077D01*
X807455Y2014788D01*
X808321Y2015077D01*
X808971Y2015798D01*
X809404Y2016664D01*
X809729Y2017819D01*
X809837Y2019118D01*
X809729Y2020418D01*
X809404Y2021573D01*
X808971Y2022439D01*
X808321Y2023160D01*
X807455Y2023449D01*
G01X816116D02*
X815250Y2023160D01*
X814600Y2022439D01*
X814167Y2021573D01*
X813842Y2020418D01*
X813734Y2019118D01*
X813842Y2017819D01*
X814167Y2016664D01*
X814600Y2015798D01*
X815250Y2015077D01*
X816116Y2014788D01*
X816982Y2015077D01*
X817632Y2015798D01*
X818065Y2016664D01*
X818390Y2017819D01*
X818498Y2019118D01*
X818390Y2020418D01*
X818065Y2021573D01*
X817632Y2022439D01*
X816982Y2023160D01*
X816116Y2023449D01*
G01X824777Y2014499D02*
X824560Y2014644D01*
Y2014932D01*
X824777Y2015077D01*
X824994Y2014932D01*
Y2014644D01*
X824777Y2014499D01*
G01X833438Y2023449D02*
X832572Y2023160D01*
X831922Y2022439D01*
X831489Y2021573D01*
X831164Y2020418D01*
X831056Y2019118D01*
X831164Y2017819D01*
X831489Y2016664D01*
X831922Y2015798D01*
X832572Y2015077D01*
X833438Y2014788D01*
X834304Y2015077D01*
X834954Y2015798D01*
X835387Y2016664D01*
X835712Y2017819D01*
X835820Y2019118D01*
X835712Y2020418D01*
X835387Y2021573D01*
X834954Y2022439D01*
X834304Y2023160D01*
X833438Y2023449D01*
G01X842099D02*
X841233Y2023160D01*
X840583Y2022439D01*
X840150Y2021573D01*
X839825Y2020418D01*
X839717Y2019118D01*
X839825Y2017819D01*
X840150Y2016664D01*
X840583Y2015798D01*
X841233Y2015077D01*
X842099Y2014788D01*
X842965Y2015077D01*
X843615Y2015798D01*
X844048Y2016664D01*
X844373Y2017819D01*
X844481Y2019118D01*
X844373Y2020418D01*
X844048Y2021573D01*
X843615Y2022439D01*
X842965Y2023160D01*
X842099Y2023449D01*
G01X790441Y2112671D02*
Y2093734D01*
G01X811261Y54945D02*
X810395Y54656D01*
X809745Y53935D01*
X809312Y53069D01*
X808987Y51914D01*
X808879Y50614D01*
X808987Y49315D01*
X809312Y48160D01*
X809745Y47294D01*
X810395Y46573D01*
X811261Y46284D01*
X812127Y46573D01*
X812777Y47294D01*
X813210Y48160D01*
X813535Y49315D01*
X813643Y50614D01*
X813535Y51914D01*
X813210Y53069D01*
X812777Y53935D01*
X812127Y54656D01*
X811261Y54945D01*
G01X819922Y45995D02*
X819705Y46140D01*
Y46428D01*
X819922Y46573D01*
X820139Y46428D01*
Y46140D01*
X819922Y45995D01*
G01X828583Y54945D02*
X827717Y54656D01*
X827067Y53935D01*
X826634Y53069D01*
X826309Y51914D01*
X826201Y50614D01*
X826309Y49315D01*
X826634Y48160D01*
X827067Y47294D01*
X827717Y46573D01*
X828583Y46284D01*
X829449Y46573D01*
X830099Y47294D01*
X830532Y48160D01*
X830857Y49315D01*
X830965Y50614D01*
X830857Y51914D01*
X830532Y53069D01*
X830099Y53935D01*
X829449Y54656D01*
X828583Y54945D01*
G01X837244D02*
X836378Y54656D01*
X835728Y53935D01*
X835295Y53069D01*
X834970Y51914D01*
X834862Y50614D01*
X834970Y49315D01*
X835295Y48160D01*
X835728Y47294D01*
X836378Y46573D01*
X837244Y46284D01*
X838110Y46573D01*
X838760Y47294D01*
X839193Y48160D01*
X839518Y49315D01*
X839626Y50614D01*
X839518Y51914D01*
X839193Y53069D01*
X838760Y53935D01*
X838110Y54656D01*
X837244Y54945D01*
G01X868969Y44119D02*
X844823D01*
G01X846528Y90969D02*
Y93489D01*
G01X845347Y91560D02*
Y92898D01*
G01Y91560D02*
X846528Y90969D01*
G01X868969D02*
X846528D01*
G01X845347Y92898D02*
X846528Y93489D01*
G01X845347Y102898D02*
X846528Y103489D01*
G01X845347Y112898D02*
X846528Y113489D01*
G01X845347Y122898D02*
X846528Y123489D01*
G01X845347Y132898D02*
X846528Y133489D01*
G01Y130969D02*
Y133489D01*
G01Y120969D02*
Y123489D01*
G01Y110969D02*
Y113489D01*
G01Y100969D02*
Y103489D01*
G01X845347Y131560D02*
Y132898D01*
G01Y121560D02*
Y122898D01*
G01Y111560D02*
Y112898D01*
G01Y101560D02*
Y102898D01*
G01Y131560D02*
X846528Y130969D01*
G01X845347Y121560D02*
X846528Y120969D01*
G01X845347Y111560D02*
X846528Y110969D01*
G01X845347Y101560D02*
X846528Y100969D01*
G01X868969Y133489D02*
X846528D01*
G01X868969Y130969D02*
X846528D01*
G01X868969Y123489D02*
X846528D01*
G01X868969Y120969D02*
X846528D01*
G01X868969Y113489D02*
X846528D01*
G01X868969Y110969D02*
X846528D01*
G01X868969Y103489D02*
X846528D01*
G01X868969Y100969D02*
X846528D01*
G01X868969Y93489D02*
X846528D01*
G01X845347Y526127D02*
X846528Y526717D01*
G01X845347Y536127D02*
X846528Y536717D01*
G01X845347Y546127D02*
X846528Y546717D01*
G01Y544198D02*
Y546717D01*
G01Y534198D02*
Y536717D01*
G01Y524198D02*
Y526717D01*
G01X845347Y544788D02*
Y546127D01*
G01Y534788D02*
Y536127D01*
G01Y524788D02*
Y526127D01*
G01Y544788D02*
X846528Y544198D01*
G01X845347Y534788D02*
X846528Y534198D01*
G01X845347Y524788D02*
X846528Y524198D01*
G01X868969Y546717D02*
X846528D01*
G01X868969Y544198D02*
X846528D01*
G01X868969Y536717D02*
X846528D01*
G01X868969Y534198D02*
X846528D01*
G01X868969Y526717D02*
X846528D01*
G01X868969Y524198D02*
X846528D01*
G01X845347Y556127D02*
X846528Y556717D01*
G01X845347Y566127D02*
X846528Y566717D01*
G01Y564198D02*
Y566717D01*
G01Y554198D02*
Y556717D01*
G01X845347Y564788D02*
Y566127D01*
G01Y554788D02*
Y556127D01*
G01Y564788D02*
X846528Y564198D01*
G01X845347Y554788D02*
X846528Y554198D01*
G01X868969Y566717D02*
X846528D01*
G01X868969Y564198D02*
X846528D01*
G01X868969Y556717D02*
X846528D01*
G01X868969Y554198D02*
X846528D01*
G01X845347Y785969D02*
X846528Y786560D01*
G01X845347Y795969D02*
X846528Y796560D01*
G01X845347Y805969D02*
X846528Y806560D01*
G01Y804040D02*
Y806560D01*
G01Y794040D02*
Y796560D01*
G01Y784040D02*
Y786560D01*
G01X845347Y804631D02*
Y805969D01*
G01Y794631D02*
Y795969D01*
G01Y784631D02*
Y785969D01*
G01Y804631D02*
X846528Y804040D01*
G01X868969Y806560D02*
X846528D01*
G01X868969Y804040D02*
X846528D01*
G01X868969Y796560D02*
X846528D01*
G01X868969Y794040D02*
X846528D01*
G01X868969Y786560D02*
X846528D01*
G01X868969Y784040D02*
X846528D01*
G01X845347Y794631D02*
X846528Y794040D01*
G01X845347Y784631D02*
X846528Y784040D01*
G01X845347Y815969D02*
X846528Y816560D01*
G01X845347Y825969D02*
X846528Y826560D01*
G01Y824040D02*
Y826560D01*
G01Y814040D02*
Y816560D01*
G01X845347Y824631D02*
Y825969D01*
G01Y814631D02*
Y815969D01*
G01Y824631D02*
X846528Y824040D01*
G01X845347Y814631D02*
X846528Y814040D01*
G01X868969Y826560D02*
X846528D01*
G01X868969Y824040D02*
X846528D01*
G01X868969Y816560D02*
X846528D01*
G01X868969Y814040D02*
X846528D01*
G01X868969Y1262702D02*
X846528D01*
G01X868969Y1260182D02*
X846528D01*
G01X868969Y1252702D02*
X846528D01*
G01X868969Y1250182D02*
X846528D01*
G01X868969Y1242702D02*
X846528D01*
G01X868969Y1240182D02*
X846528D01*
G01X845347Y1260772D02*
X846528Y1260182D01*
G01X845347Y1250772D02*
X846528Y1250182D01*
G01X868969Y1232702D02*
X846528D01*
G01X868969Y1230182D02*
X846528D01*
G01X845347Y1240772D02*
X846528Y1240182D01*
G01X845347Y1230772D02*
X846528Y1230182D01*
G01Y1260182D02*
Y1262702D01*
G01Y1250182D02*
Y1252702D01*
G01Y1240182D02*
Y1242702D01*
G01Y1230182D02*
Y1232702D01*
G01X845347Y1260772D02*
Y1262111D01*
G01Y1250772D02*
Y1252111D01*
G01Y1240772D02*
Y1242111D01*
G01Y1230772D02*
Y1232111D01*
G01D02*
X846528Y1232702D01*
G01X845347Y1242111D02*
X846528Y1242702D01*
G01X845347Y1252111D02*
X846528Y1252702D01*
G01X845347Y1262111D02*
X846528Y1262702D01*
G01X868969Y1272702D02*
X846528D01*
G01X868969Y1270182D02*
X846528D01*
G01X845347Y1270772D02*
X846528Y1270182D01*
G01D02*
Y1272702D01*
G01X845347Y1270772D02*
Y1272111D01*
G01D02*
X846528Y1272702D01*
G01X868969Y1522544D02*
X846528D01*
G01X868969Y1520024D02*
X846528D01*
G01X868969Y1512544D02*
X846528D01*
G01X868969Y1510024D02*
X846528D01*
G01X868969Y1502544D02*
X846528D01*
G01X868969Y1500024D02*
X846528D01*
G01X868969Y1492544D02*
X846528D01*
G01X868969Y1490024D02*
X846528D01*
G01X845347Y1520615D02*
X846528Y1520024D01*
G01X845347Y1510615D02*
X846528Y1510024D01*
G01X845347Y1500615D02*
X846528Y1500024D01*
G01X845347Y1490615D02*
X846528Y1490024D01*
G01Y1520024D02*
Y1522544D01*
G01Y1510024D02*
Y1512544D01*
G01Y1500024D02*
Y1502544D01*
G01Y1490024D02*
Y1492544D01*
G01X845347Y1520615D02*
Y1521954D01*
G01Y1510615D02*
Y1511954D01*
G01Y1500615D02*
Y1501954D01*
G01Y1490615D02*
Y1491954D01*
G01D02*
X846528Y1492544D01*
G01X845347Y1501954D02*
X846528Y1502544D01*
G01X845347Y1511954D02*
X846528Y1512544D01*
G01X845347Y1521954D02*
X846528Y1522544D01*
G01X868969Y1532544D02*
X846528D01*
G01X868969Y1530024D02*
X846528D01*
G01X845347Y1530615D02*
X846528Y1530024D01*
G01D02*
Y1532544D01*
G01X845347Y1530615D02*
Y1531954D01*
G01D02*
X846528Y1532544D01*
G01X868969Y1933253D02*
X846528D01*
G01X868969Y1925772D02*
X846528D01*
G01X868969Y1923253D02*
X846528D01*
G01X845347Y1933843D02*
X846528Y1933253D01*
G01X845347Y1923843D02*
X846528Y1923253D01*
G01Y1933253D02*
Y1935772D01*
G01Y1923253D02*
Y1925772D01*
G01X845347Y1923843D02*
Y1925182D01*
G01D02*
X846528Y1925772D01*
G01X868969Y1965772D02*
X846528D01*
G01X868969Y1963253D02*
X846528D01*
G01X868969Y1955772D02*
X846528D01*
G01X868969Y1953253D02*
X846528D01*
G01X868969Y1945772D02*
X846528D01*
G01X868969Y1943253D02*
X846528D01*
G01X868969Y1935772D02*
X846528D01*
G01X845347Y1963843D02*
X846528Y1963253D01*
G01X845347Y1953843D02*
X846528Y1953253D01*
G01X845347Y1943843D02*
X846528Y1943253D01*
G01Y1963253D02*
Y1965772D01*
G01Y1953253D02*
Y1955772D01*
G01Y1943253D02*
Y1945772D01*
G01X845347Y1963843D02*
Y1965182D01*
G01Y1953843D02*
Y1955182D01*
G01Y1943843D02*
Y1945182D01*
G01Y1933843D02*
Y1935182D01*
G01D02*
X846528Y1935772D01*
G01X845347Y1945182D02*
X846528Y1945772D01*
G01X845347Y1955182D02*
X846528Y1955772D01*
G01X845347Y1965182D02*
X846528Y1965772D01*
G01X868969Y2012623D02*
X849678D01*
G01X900465Y-80235D02*
X900749Y-77773D01*
X901175Y-75690D01*
X901743Y-73797D01*
X902453Y-71714D01*
X903590Y-68873D01*
X897908D01*
G01X858143Y-26315D02*
X858432Y-27181D01*
X859153Y-27831D01*
X860019Y-28264D01*
X861174Y-28589D01*
X862474Y-28697D01*
X863773Y-28589D01*
X864928Y-28264D01*
X865794Y-27831D01*
X866515Y-27181D01*
X866804Y-26315D01*
X866515Y-25449D01*
X865794Y-24799D01*
X864928Y-24366D01*
X863773Y-24041D01*
X862474Y-23933D01*
X861174Y-24041D01*
X860019Y-24366D01*
X859153Y-24799D01*
X858432Y-25449D01*
X858143Y-26315D01*
G01X867093Y-17654D02*
X866948Y-17871D01*
X866660D01*
X866515Y-17654D01*
X866660Y-17437D01*
X866948D01*
X867093Y-17654D01*
G01X858143Y-8993D02*
X858432Y-9859D01*
X859153Y-10509D01*
X860019Y-10942D01*
X861174Y-11267D01*
X862474Y-11375D01*
X863773Y-11267D01*
X864928Y-10942D01*
X865794Y-10509D01*
X866515Y-9859D01*
X866804Y-8993D01*
X866515Y-8127D01*
X865794Y-7477D01*
X864928Y-7044D01*
X863773Y-6719D01*
X862474Y-6611D01*
X861174Y-6719D01*
X860019Y-7044D01*
X859153Y-7477D01*
X858432Y-8127D01*
X858143Y-8993D01*
G01Y-332D02*
X858432Y-1198D01*
X859153Y-1848D01*
X860019Y-2281D01*
X861174Y-2606D01*
X862474Y-2714D01*
X863773Y-2606D01*
X864928Y-2281D01*
X865794Y-1848D01*
X866515Y-1198D01*
X866804Y-332D01*
X866515Y534D01*
X865794Y1184D01*
X864928Y1617D01*
X863773Y1942D01*
X862474Y2050D01*
X861174Y1942D01*
X860019Y1617D01*
X859153Y1184D01*
X858432Y534D01*
X858143Y-332D01*
G01X868969Y44119D02*
Y7247D01*
G01X882877Y90969D02*
G03Y93489I1998J1260D01*
G01D02*
G03Y90969I1998J-1260D01*
G01X905977Y68922D02*
G03I-7086J0D01*
G01X868969Y48056D02*
G03X872906Y44119I3937J0D01*
G01X868969Y48056D02*
G03X872906Y44119I3937J0D01*
G01X884206Y91560D02*
X883615Y90969D01*
G01X899628Y90470D02*
Y89486D01*
G01X895942Y95063D02*
Y90470D01*
G01X894937D02*
Y95063D01*
G01X891754Y89486D02*
Y90470D01*
G01X886135Y93489D02*
Y90969D01*
G01X885544Y91560D02*
Y92898D01*
G01X884206Y91560D02*
Y92898D01*
G01X883615Y93489D02*
Y90969D01*
G01X882631Y93489D02*
Y90969D01*
G01X878969Y87229D02*
Y137229D01*
G01X877788D02*
Y87229D01*
G01X868969D02*
Y137229D01*
G01Y87229D02*
Y137229D01*
G01Y87229D02*
Y137229D01*
G01Y48056D02*
Y87229D01*
G01Y48056D02*
Y87229D01*
G01X886135Y90969D02*
X885544Y91560D01*
G01X884206D02*
X885544D01*
G01X878969Y90969D02*
X877788D01*
G01X886135D02*
X878969D01*
G01X895942Y90470D02*
X899628D01*
G01X891754D02*
X894937D01*
G01X899628Y89486D02*
X891754D01*
G01X868969Y88804D02*
X878969D01*
G01X868969Y88017D02*
X878969D01*
G01X868969Y87229D02*
X878969D01*
G01X870095Y45300D02*
X922119D01*
G01X933930Y44119D02*
X872906D01*
G01X933930D02*
X872906D01*
G01X882877Y100969D02*
G03Y103489I1998J1260D01*
G01Y110969D02*
G03Y113489I1998J1260D01*
G01Y120969D02*
G03Y123489I1998J1260D01*
G01Y130969D02*
G03Y133489I1998J1260D01*
G01Y103489D02*
G03Y100969I1998J-1260D01*
G01Y113489D02*
G03Y110969I1998J-1260D01*
G01Y123489D02*
G03Y120969I1998J-1260D01*
G01Y133489D02*
G03Y130969I1998J-1260D01*
G01X897283Y101461D02*
X897785Y101625D01*
G01X894100Y107038D02*
X893597Y106874D01*
G01X887973Y132201D02*
X887848Y132160D01*
G01Y132406D02*
X887973Y132447D01*
G01X894770Y114256D02*
X895607Y114584D01*
G01X894770Y121638D02*
X895607Y121966D01*
G01X897785Y101625D02*
X898455Y101953D01*
G01X893597Y106874D02*
X892927Y106546D01*
G01X895607Y111139D02*
X895272Y110975D01*
G01X895607Y113764D02*
X895272Y113600D01*
G01X895607Y118521D02*
X895272Y118357D01*
G01X895607Y121146D02*
X895272Y120982D01*
G01X897283Y102281D02*
X898288Y102937D01*
G01X894100Y106218D02*
X893094Y105562D01*
G01X887680Y132283D02*
X887848Y132406D01*
G01X898455Y101953D02*
X898958Y102445D01*
G01X892927Y106546D02*
X892424Y106054D01*
G01X895272Y110975D02*
X895105Y110811D01*
G01X894435Y111304D02*
X894937Y111796D01*
G01X895272Y113600D02*
X895105Y113436D01*
G01X894435Y113928D02*
X894770Y114256D01*
G01X895272Y118357D02*
X895105Y118193D01*
G01X894435Y118685D02*
X894937Y119178D01*
G01X885544Y92898D02*
X886135Y93489D01*
G01X895272Y120982D02*
X895105Y120818D01*
G01X894435Y121310D02*
X894770Y121638D01*
G01X887848Y132160D02*
X887764Y132078D01*
G01X885544Y102898D02*
X886135Y103489D01*
G01X884206Y101560D02*
X883615Y100969D01*
G01X885544Y112898D02*
X886135Y113489D01*
G01X884206Y111560D02*
X883615Y110969D01*
G01X885544Y122898D02*
X886135Y123489D01*
G01X884206Y121560D02*
X883615Y120969D01*
G01X885544Y132898D02*
X886135Y133489D01*
G01X884206Y131560D02*
X883615Y130969D01*
G01X887555Y132119D02*
X887680Y132283D01*
G01X898288Y102937D02*
X898623Y103430D01*
G01X893094Y105562D02*
X892759Y105070D01*
G01X898958Y102445D02*
X899461Y103265D01*
G01X892424Y106054D02*
X891922Y105234D01*
G01X895105Y110811D02*
X894937Y110483D01*
G01X895105Y113436D02*
X894937Y113108D01*
G01X895105Y118193D02*
X894937Y117865D01*
G01X895105Y120818D02*
X894937Y120490D01*
G01X894267Y110811D02*
X894435Y111304D01*
G01X894267Y113436D02*
X894435Y113928D01*
G01X894267Y118193D02*
X894435Y118685D01*
G01X894267Y120818D02*
X894435Y121310D01*
G01X887764Y132078D02*
X887722Y131955D01*
G01X898623Y103430D02*
X898790Y104250D01*
G01X892759Y105070D02*
X892592Y104250D01*
G01X887513Y131914D02*
X887555Y132119D01*
G01X899461Y103265D02*
X899628Y104250D01*
G01X891922Y105234D02*
X891754Y104250D01*
G01X899628Y96048D02*
Y95063D01*
G01Y111960D02*
Y111139D01*
G01Y109335D02*
Y108515D01*
G01Y114584D02*
Y113764D01*
G01Y116717D02*
Y115897D01*
G01Y119342D02*
Y118521D01*
G01Y121966D02*
Y121146D01*
G01X896948Y99985D02*
Y97360D01*
G01X896277D02*
Y99985D01*
G01X894937D02*
Y97360D01*
G01Y110483D02*
Y110155D01*
G01Y113108D02*
Y112616D01*
G01Y117865D02*
Y117537D01*
G01Y120490D02*
Y119998D01*
G01X894267Y120162D02*
Y120818D01*
G01Y117537D02*
Y118193D01*
G01Y115897D02*
Y116717D01*
G01Y112780D02*
Y113436D01*
G01Y110155D02*
Y110811D01*
G01Y108515D02*
Y109335D01*
G01Y97360D02*
Y99985D01*
G01X891754Y95063D02*
Y96048D01*
G01X889481Y131176D02*
Y130930D01*
G01Y133268D02*
Y133021D01*
G01X888602Y131914D02*
Y131176D01*
G01X888350D02*
Y131955D01*
G01X887722D02*
Y131176D01*
G01X887513Y133021D02*
Y133268D01*
G01Y130930D02*
Y131914D01*
G01X886135Y103489D02*
Y100969D01*
G01Y113489D02*
Y110969D01*
G01Y123489D02*
Y120969D01*
G01Y133489D02*
Y130969D01*
G01X885544Y131560D02*
Y132898D01*
G01Y121560D02*
Y122898D01*
G01Y111560D02*
Y112898D01*
G01Y101560D02*
Y102898D01*
G01X884206Y131560D02*
Y132898D01*
G01Y121560D02*
Y122898D01*
G01Y111560D02*
Y112898D01*
G01Y101560D02*
Y102898D01*
G01X883615Y103489D02*
Y100969D01*
G01Y113489D02*
Y110969D01*
G01Y123489D02*
Y120969D01*
G01Y133489D02*
Y130969D01*
G01X882631Y103489D02*
Y100969D01*
G01Y113489D02*
Y110969D01*
G01Y123489D02*
Y120969D01*
G01Y133489D02*
Y130969D01*
G01X868969Y137229D02*
Y258883D01*
G01Y137229D02*
Y258883D01*
G01X899628Y104250D02*
X899461Y105234D01*
G01X891754Y104250D02*
X891922Y103265D01*
G01X898790Y104250D02*
X898623Y105070D01*
G01X888560Y132119D02*
X888602Y131914D01*
G01X892592Y104250D02*
X892759Y103430D01*
G01X894435Y119670D02*
X894267Y120162D01*
G01X894937Y117537D02*
X895105Y117045D01*
G01X894435D02*
X894267Y117537D01*
G01X888350Y131955D02*
X888308Y132078D01*
G01X894435Y112288D02*
X894267Y112780D01*
G01X894937Y110155D02*
X895105Y109663D01*
G01X894435D02*
X894267Y110155D01*
G01X894937Y119998D02*
X895105Y119670D01*
G01X894937Y112616D02*
X895105Y112288D01*
G01X899461Y105234D02*
X898958Y106054D01*
G01X891922Y103265D02*
X892424Y102445D01*
G01X898623Y105070D02*
X898288Y105562D01*
G01X892759Y103430D02*
X893094Y102937D01*
G01X888434Y132283D02*
X888560Y132119D01*
G01X884206Y132898D02*
X883615Y133489D01*
G01X886135Y130969D02*
X885544Y131560D01*
G01X884206Y122898D02*
X883615Y123489D01*
G01X886135Y120969D02*
X885544Y121560D01*
G01X886135Y110969D02*
X885544Y111560D01*
G01X884206Y112898D02*
X883615Y113489D01*
G01X884206Y102898D02*
X883615Y103489D01*
G01X886135Y100969D02*
X885544Y101560D01*
G01X884206Y92898D02*
X883615Y93489D01*
G01X888308Y132078D02*
X888225Y132160D01*
G01X895105Y119670D02*
X895272Y119506D01*
G01X894937Y119178D02*
X894435Y119670D01*
G01X895105Y117045D02*
X895440Y116717D01*
G01X894770D02*
X894435Y117045D01*
G01X895105Y112288D02*
X895272Y112124D01*
G01X894937Y111796D02*
X894435Y112288D01*
G01X898958Y106054D02*
X898455Y106546D01*
G01X895105Y109663D02*
X895440Y109335D01*
G01X894770D02*
X894435Y109663D01*
G01X892424Y102445D02*
X892927Y101953D01*
G01X887848Y133021D02*
X888141Y132775D01*
G01X887806D02*
X887513Y133021D01*
G01X888267Y132406D02*
X888434Y132283D01*
G01X898288Y105562D02*
X897283Y106218D01*
G01X893094Y102937D02*
X894100Y102281D01*
G01X895272Y119506D02*
X895607Y119342D01*
G01X895272Y112124D02*
X895607Y111960D01*
G01X898455Y106546D02*
X897785Y106874D01*
G01X892927Y101953D02*
X893597Y101625D01*
G01X888141Y132447D02*
X888267Y132406D01*
G01X888225Y132160D02*
X888099Y132201D01*
G01X897785Y106874D02*
X897283Y107038D01*
G01X893597Y101625D02*
X894100Y101461D01*
G01X868969Y137229D02*
X878969D01*
G01Y136442D02*
X868969D01*
G01X878969Y135654D02*
X868969D01*
G01X878969Y133489D02*
X877788D01*
G01X886135D02*
X878969D01*
G01X887513Y133268D02*
X889481D01*
G01Y133021D02*
X887848D01*
G01X885544Y132898D02*
X884206D01*
G01X888141Y132775D02*
X887806D01*
G01X887973Y132447D02*
X888141D01*
G01X888099Y132201D02*
X887973D01*
G01X884206Y131560D02*
X885544D01*
G01X887722Y131176D02*
X888350D01*
G01X888602D02*
X889481D01*
G01X878969Y130969D02*
X877788D01*
G01X886135D02*
X878969D01*
G01X889481Y130930D02*
X887513D01*
G01X868969Y128804D02*
X878969D01*
G01X868969Y128017D02*
X878969D01*
G01Y126442D02*
X868969D01*
G01X878969Y125654D02*
X868969D01*
G01X878969Y123489D02*
X877788D01*
G01X886135D02*
X878969D01*
G01X885544Y122898D02*
X884206D01*
G01X895607Y121966D02*
X899628D01*
G01X884206Y121560D02*
X885544D01*
G01X899628Y121146D02*
X895607D01*
G01X878969Y120969D02*
X877788D01*
G01X886135D02*
X878969D01*
G01X895607Y119342D02*
X899628D01*
G01X868969Y118804D02*
X878969D01*
G01X899628Y118521D02*
X895607D01*
G01X868969Y118017D02*
X878969D01*
G01X895440Y116717D02*
X899628D01*
G01X894267D02*
X894770D01*
G01X878969Y116442D02*
X868969D01*
G01X899628Y115897D02*
X894267D01*
G01X878969Y115654D02*
X868969D01*
G01X895607Y114584D02*
X899628D01*
G01Y113764D02*
X895607D01*
G01X878969Y113489D02*
X877788D01*
G01X886135D02*
X878969D01*
G01X885544Y112898D02*
X884206D01*
G01X895105Y106382D02*
X894100Y106218D01*
G01X896277Y102117D02*
X897283Y102281D01*
G01X894937Y107202D02*
X894100Y107038D01*
G01X896445Y101297D02*
X897283Y101461D01*
G01Y107038D02*
X896445Y107202D01*
G01X894100Y101461D02*
X894937Y101297D01*
G01X897283Y106218D02*
X896277Y106382D01*
G01X894100Y102281D02*
X895105Y102117D01*
G01X895607Y111960D02*
X899628D01*
G01X884206Y111560D02*
X885544D01*
G01X899628Y111139D02*
X895607D01*
G01X878969Y110969D02*
X877788D01*
G01X886135D02*
X878969D01*
G01X895440Y109335D02*
X899628D01*
G01X894267D02*
X894770D01*
G01X868969Y108804D02*
X878969D01*
G01X899628Y108515D02*
X894267D01*
G01X868969Y108017D02*
X878969D01*
G01X896445Y107202D02*
X894937D01*
G01X878969Y106442D02*
X868969D01*
G01X896277Y106382D02*
X895105D01*
G01X878969Y105654D02*
X868969D01*
G01X878969Y103489D02*
X877788D01*
G01X886135D02*
X878969D01*
G01X885544Y102898D02*
X884206D01*
G01X895105Y102117D02*
X896277D01*
G01X884206Y101560D02*
X885544D01*
G01X894937Y101297D02*
X896445D01*
G01X878969Y100969D02*
X877788D01*
G01X886135D02*
X878969D01*
G01X896277Y99985D02*
X896948D01*
G01X894267D02*
X894937D01*
G01X868969Y98804D02*
X878969D01*
G01X868969Y98017D02*
X878969D01*
G01X894937Y97360D02*
X894267D01*
G01X896948D02*
X896277D01*
G01X878969Y96442D02*
X868969D01*
G01X891754Y96048D02*
X899628D01*
G01X878969Y95654D02*
X868969D01*
G01X894937Y95063D02*
X891754D01*
G01X899628D02*
X895942D01*
G01X878969Y93489D02*
X877788D01*
G01X886135D02*
X878969D01*
G01X885544Y92898D02*
X884206D01*
G01X905977Y155536D02*
G03I-7086J0D01*
G01X904402Y201599D02*
G03I-7874J0D01*
G01X912276D02*
G03I-15748J0D01*
G01X922119Y179158D02*
X868969D01*
G01X886848Y274001D02*
G03X886258Y273410I1J-591D01*
G01X886489Y256560D02*
G03X887080Y255969I591J0D01*
G01X886489Y261678D02*
G03X885898Y262268I-590J0D01*
G01X880387Y267702D02*
G03X880190Y267505I0J-197D01*
G01Y266166D02*
G03X880387Y265969I197J0D01*
G01Y264001D02*
G03X880190Y263804I0J-197D01*
G01Y262465D02*
G03X880387Y262268I197J0D01*
G01X866017Y271087D02*
G03Y258883I0J-6102D01*
G01X885471Y270064D02*
X882158Y267702D01*
G01X897709Y271442D02*
X899284Y273017D01*
G01X899678Y273410D02*
X899284Y273017D01*
G01X897709Y259867D02*
X899284Y262702D01*
G01X899678Y263410D02*
X899284Y262702D01*
G01X880190Y269276D02*
X883103Y275969D01*
G01X901646D02*
Y278174D01*
G01Y265969D02*
Y274001D01*
G01Y255969D02*
Y264001D01*
G01Y251796D02*
Y254001D01*
G01Y255133D02*
Y254887D01*
G01X901253Y255969D02*
Y254001D01*
G01Y265969D02*
Y264001D01*
G01Y275969D02*
Y274001D01*
G01X900505Y255969D02*
Y254001D01*
G01Y265969D02*
Y264001D01*
G01Y275969D02*
Y274001D01*
G01X899678Y254887D02*
Y255133D01*
G01X899284Y273017D02*
Y276560D01*
G01Y262702D02*
Y267268D01*
G01Y264001D02*
Y265969D01*
G01Y253410D02*
Y257032D01*
G01Y255969D02*
Y254001D01*
G01Y275969D02*
Y274001D01*
G01X897709Y253410D02*
Y276560D01*
G01X896528Y271997D02*
Y258817D01*
G01X886489Y261678D02*
Y256560D01*
G01X886258Y273410D02*
Y270064D01*
G01X880387Y262268D02*
Y260062D01*
G01Y265969D02*
Y264001D01*
G01X880190Y272465D02*
Y258883D01*
G01Y273015D02*
Y258817D01*
G01X878812Y275418D02*
Y254552D01*
G01X876253Y272465D02*
Y258883D01*
G01X875465Y271875D02*
Y258883D01*
G01X874875Y251796D02*
Y278174D01*
G01X868969Y271087D02*
Y386580D01*
G01Y271087D02*
Y386580D01*
G01Y258883D02*
Y271087D01*
G01Y258883D02*
Y271087D01*
G01X866017Y258883D02*
Y271087D01*
G01X863064Y259654D02*
Y247859D01*
G01Y270316D02*
Y259654D01*
G01Y282111D02*
Y270316D01*
G01X883024Y254001D02*
X880190Y260515D01*
G01X899284Y267268D02*
X897709Y270103D01*
G01X899284Y267268D02*
X899678Y266560D01*
G01X899284Y257032D02*
X899678Y256560D01*
G01X899284Y257032D02*
X897709Y258922D01*
G01X901353Y255379D02*
X901646Y255133D01*
G01X901311D02*
X901253Y255182D01*
G01D02*
X901018Y255379D01*
G01X863064Y282111D02*
X905583D01*
G01X874875Y278174D02*
X901646D01*
G01X897709Y276560D02*
X899284D01*
G01X901646D02*
X899284D01*
G01X874875Y276166D02*
X899284D01*
G01Y275969D02*
X901253D01*
G01X899284D02*
X883103D01*
G01X901646D02*
X901253D01*
G01D02*
X899284D01*
G01Y275418D02*
X878812D01*
G01X899284Y274001D02*
X901253D01*
G01X886848D02*
X899284D01*
G01X901646D02*
X901253D01*
G01D02*
X899284D01*
G01X901646Y273410D02*
X899678D01*
G01X880190Y273015D02*
X874875D01*
G01X876253Y272465D02*
X880190D01*
G01X896528Y271997D02*
X880190D01*
G01X875465Y271875D02*
X876253D01*
G01X874875Y271087D02*
X866017D01*
G01X875465D02*
X874875D01*
G01X886258Y270064D02*
X885471D01*
G01X882158Y267702D02*
X880387D01*
G01X901646Y266560D02*
X899678D01*
G01X899284Y265969D02*
X901253D01*
G01X880387D02*
X899284D01*
G01X901646D02*
X901253D01*
G01D02*
X899284D01*
G01Y264001D02*
X880387D01*
G01X901253D02*
X899284D01*
G01X901646D02*
X901253D01*
G01D02*
X899284D01*
G01X901646Y263410D02*
X899678D01*
G01X880387Y262268D02*
X885898D01*
G01X874875Y258883D02*
X880190D01*
G01X874875D02*
X866017D01*
G01X880190Y258843D02*
X874875D01*
G01X896528Y258817D02*
X880190D01*
G01X901646Y256560D02*
X899678D01*
G01X899284Y255969D02*
X901253D01*
G01X887080D02*
X899284D01*
G01X901646D02*
X901253D01*
G01D02*
X899284D01*
G01X901253Y255379D02*
X901353D01*
G01X901018D02*
X901253D01*
G01Y255133D02*
X901311D01*
G01X899678D02*
X901253D01*
G01X901646Y254887D02*
X901253D01*
G01D02*
X899678D01*
G01X899284Y254552D02*
X878812D01*
G01X899284Y254001D02*
X883024D01*
G01X901253D02*
X899284D01*
G01X901646D02*
X901253D01*
G01D02*
X899284D01*
G01X874875Y253804D02*
X899284D01*
G01X897709Y253410D02*
X899284D01*
G01X901646D02*
X899284D01*
G01X874875Y251796D02*
X901646D01*
G01X863064Y247859D02*
X905583D01*
G01X886489Y384257D02*
G03X887080Y383666I591J0D01*
G01X886489Y389375D02*
G03X885898Y389965I-590J0D01*
G01X880387Y395398D02*
G03X880190Y395202I0J-197D01*
G01Y393863D02*
G03X880387Y393666I197J0D01*
G01Y391698D02*
G03X880190Y391501I0J-197D01*
G01Y390162D02*
G03X880387Y389965I197J0D01*
G01X866017Y398784D02*
G03Y386580I0J-6102D01*
G01X885471Y397761D02*
X882158Y395398D01*
G01X897709Y387564D02*
X899284Y390398D01*
G01X899678Y391107D02*
X899284Y390398D01*
G01X880190Y396973D02*
X883103Y403666D01*
G01X901646Y393666D02*
Y401698D01*
G01Y383666D02*
Y391698D01*
G01Y379493D02*
Y381698D01*
G01Y382830D02*
Y382583D01*
G01X901253Y383666D02*
Y381698D01*
G01Y393666D02*
Y391698D01*
G01X900505Y383666D02*
Y381698D01*
G01Y393666D02*
Y391698D01*
G01X899678Y382583D02*
Y382830D01*
G01X899284Y390398D02*
Y394965D01*
G01Y391698D02*
Y393666D01*
G01Y381107D02*
Y384729D01*
G01Y383666D02*
Y381698D01*
G01X897709Y381107D02*
Y404257D01*
G01X896528Y399694D02*
Y386514D01*
G01X886489Y389375D02*
Y384257D01*
G01X886258Y401107D02*
Y397761D01*
G01X880387Y389965D02*
Y387759D01*
G01Y393666D02*
Y391698D01*
G01X880190Y400712D02*
Y386514D01*
G01Y400162D02*
Y386580D01*
G01X878812Y403115D02*
Y382249D01*
G01X876253Y400162D02*
Y386580D01*
G01X875465Y399572D02*
Y386580D01*
G01X874875Y379493D02*
Y405871D01*
G01X868969Y386580D02*
Y398784D01*
G01Y386580D02*
Y398784D01*
G01X866017Y386580D02*
Y398784D01*
G01X863064Y387351D02*
Y375556D01*
G01Y398013D02*
Y387351D01*
G01Y409808D02*
Y398013D01*
G01X883024Y381698D02*
X880190Y388212D01*
G01X899284Y394965D02*
X897709Y397800D01*
G01X899284Y394965D02*
X899678Y394257D01*
G01X899284Y384729D02*
X899678Y384257D01*
G01X899284Y384729D02*
X897709Y386619D01*
G01X901353Y383076D02*
X901646Y382830D01*
G01X901311D02*
X901253Y382879D01*
G01D02*
X901018Y383076D01*
G01X886258Y397761D02*
X885471D01*
G01X882158Y395398D02*
X880387D01*
G01X901646Y394257D02*
X899678D01*
G01X899284Y393666D02*
X901253D01*
G01X880387D02*
X899284D01*
G01X901646D02*
X901253D01*
G01D02*
X899284D01*
G01Y391698D02*
X880387D01*
G01X901253D02*
X899284D01*
G01X901646D02*
X901253D01*
G01D02*
X899284D01*
G01X901646Y391107D02*
X899678D01*
G01X880387Y389965D02*
X885898D01*
G01X874875Y386580D02*
X880190D01*
G01X874875D02*
X866017D01*
G01X880190Y386540D02*
X874875D01*
G01X896528Y386514D02*
X880190D01*
G01X901646Y384257D02*
X899678D01*
G01X899284Y383666D02*
X901253D01*
G01X887080D02*
X899284D01*
G01X901646D02*
X901253D01*
G01D02*
X899284D01*
G01X901253Y383076D02*
X901353D01*
G01X901018D02*
X901253D01*
G01Y382830D02*
X901311D01*
G01X899678D02*
X901253D01*
G01X901646Y382583D02*
X901253D01*
G01D02*
X899678D01*
G01X899284Y382249D02*
X878812D01*
G01X899284Y381698D02*
X883024D01*
G01X901253D02*
X899284D01*
G01X901646D02*
X901253D01*
G01D02*
X899284D01*
G01X874875Y381501D02*
X899284D01*
G01X897709Y381107D02*
X899284D01*
G01X901646D02*
X899284D01*
G01X874875Y379493D02*
X901646D01*
G01X863064Y375556D02*
X905583D01*
G01X886848Y401698D02*
G03X886258Y401107I1J-591D01*
G01X897709Y399139D02*
X899284Y400713D01*
G01X899678Y401107D02*
X899284Y400713D01*
G01X901646Y403666D02*
Y405871D01*
G01X901253Y403666D02*
Y401698D01*
G01X900505Y403666D02*
Y401698D01*
G01X899284Y400713D02*
Y404257D01*
G01Y403666D02*
Y401698D01*
G01X868969Y398784D02*
Y520457D01*
G01Y398784D02*
Y520457D01*
G01X863064Y409808D02*
X905583D01*
G01X874875Y405871D02*
X901646D01*
G01X897709Y404257D02*
X899284D01*
G01X901646D02*
X899284D01*
G01X874875Y403863D02*
X899284D01*
G01Y403666D02*
X901253D01*
G01X899284D02*
X883103D01*
G01X901646D02*
X901253D01*
G01D02*
X899284D01*
G01Y403115D02*
X878812D01*
G01X899284Y401698D02*
X901253D01*
G01X886848D02*
X899284D01*
G01X901646D02*
X901253D01*
G01D02*
X899284D01*
G01X901646Y401107D02*
X899678D01*
G01X880190Y400712D02*
X874875D01*
G01X876253Y400162D02*
X880190D01*
G01X896528Y399694D02*
X880190D01*
G01X875465Y399572D02*
X876253D01*
G01X874875Y398784D02*
X866017D01*
G01X875465D02*
X874875D01*
G01X905977Y502150D02*
G03I-7086J0D01*
G01X868969Y478528D02*
X922119D01*
G01X882877Y524198D02*
G03Y526717I1998J1260D01*
G01Y534198D02*
G03Y536717I1998J1260D01*
G01Y544198D02*
G03Y546717I1998J1260D01*
G01Y526717D02*
G03Y524198I1998J-1260D01*
G01Y536717D02*
G03Y534198I1998J-1260D01*
G01Y546717D02*
G03Y544198I1998J-1260D01*
G01X901079Y543876D02*
X900576Y543712D01*
G01X901749Y551094D02*
X902586Y551422D01*
G01X900576Y543712D02*
X899906Y543384D01*
G01X902586Y547977D02*
X902251Y547813D01*
G01X902586Y550602D02*
X902251Y550438D01*
G01X901079Y543056D02*
X900073Y542400D01*
G01X899906Y543384D02*
X899403Y542892D01*
G01X902251Y547813D02*
X902084Y547649D01*
G01X901414Y548141D02*
X901916Y548633D01*
G01X902251Y550438D02*
X902084Y550274D01*
G01X901414Y550766D02*
X901749Y551094D01*
G01X885544Y526127D02*
X886135Y526717D01*
G01X884206Y524788D02*
X883615Y524198D01*
G01X885544Y536127D02*
X886135Y536717D01*
G01X884206Y534788D02*
X883615Y534198D01*
G01X885544Y546127D02*
X886135Y546717D01*
G01X884206Y544788D02*
X883615Y544198D01*
G01X900073Y542400D02*
X899738Y541908D01*
G01X899403Y542892D02*
X898901Y542072D01*
G01X902084Y547649D02*
X901916Y547321D01*
G01X902084Y550274D02*
X901916Y549946D01*
G01X901246Y547649D02*
X901414Y548141D01*
G01X901246Y550274D02*
X901414Y550766D01*
G01X899738Y541908D02*
X899571Y541087D01*
G01X898901Y542072D02*
X898733Y541087D01*
G01X903256Y534198D02*
Y536822D01*
G01X902921Y531901D02*
Y527308D01*
G01X901916D02*
Y531901D01*
G01Y536822D02*
Y534198D01*
G01Y547321D02*
Y546993D01*
G01Y549946D02*
Y549454D01*
G01X901246Y549618D02*
Y550274D01*
G01Y546993D02*
Y547649D01*
G01Y545352D02*
Y546173D01*
G01Y534198D02*
Y536822D01*
G01X898733Y531901D02*
Y532885D01*
G01Y526324D02*
Y527308D01*
G01X886135Y526717D02*
Y524198D01*
G01Y536717D02*
Y534198D01*
G01Y546717D02*
Y544198D01*
G01X885544Y544788D02*
Y546127D01*
G01Y534788D02*
Y536127D01*
G01Y524788D02*
Y526127D01*
G01X884206Y544788D02*
Y546127D01*
G01Y534788D02*
Y536127D01*
G01Y524788D02*
Y526127D01*
G01X883615Y526717D02*
Y524198D01*
G01Y536717D02*
Y534198D01*
G01Y546717D02*
Y544198D01*
G01X882631Y526717D02*
Y524198D01*
G01Y536717D02*
Y534198D01*
G01Y546717D02*
Y544198D01*
G01X878969Y520457D02*
Y570457D01*
G01X877788D02*
Y520457D01*
G01X868969D02*
Y570457D01*
G01Y520457D02*
Y570457D01*
G01Y520457D02*
Y570457D01*
G01X898733Y541087D02*
X898901Y540103D01*
G01X899571Y541087D02*
X899738Y540267D01*
G01X901414Y549125D02*
X901246Y549618D01*
G01X901916Y546993D02*
X902084Y546501D01*
G01X901414D02*
X901246Y546993D01*
G01X901916Y549454D02*
X902084Y549125D01*
G01X898901Y540103D02*
X899403Y539283D01*
G01X899738Y540267D02*
X900073Y539775D01*
G01X902084Y549125D02*
X902251Y548961D01*
G01X901916Y548633D02*
X901414Y549125D01*
G01X902084Y546501D02*
X902419Y546173D01*
G01X901749D02*
X901414Y546501D01*
G01X884206Y546127D02*
X883615Y546717D01*
G01X886135Y544198D02*
X885544Y544788D01*
G01X884206Y536127D02*
X883615Y536717D01*
G01X886135Y534198D02*
X885544Y534788D01*
G01X884206Y526127D02*
X883615Y526717D01*
G01X886135Y524198D02*
X885544Y524788D01*
G01X899403Y539283D02*
X899906Y538791D01*
G01X900073Y539775D02*
X901079Y539119D01*
G01X902251Y548961D02*
X902586Y548797D01*
G01X899906Y538791D02*
X900576Y538463D01*
G01D02*
X901079Y538299D01*
G01X904262Y543876D02*
X903424Y544040D01*
G01X901079Y538299D02*
X901916Y538135D01*
G01X904262Y543056D02*
X903256Y543220D01*
G01X901079Y539119D02*
X902084Y538955D01*
G01X868969Y552032D02*
X878969D01*
G01X902586Y551422D02*
X906607D01*
G01X868969Y551245D02*
X878969D01*
G01X906607Y550602D02*
X902586D01*
G01X878969Y549670D02*
X868969D01*
G01X878969Y548883D02*
X868969D01*
G01X902586Y548797D02*
X906607D01*
G01Y547977D02*
X902586D01*
G01X878969Y546717D02*
X877788D01*
G01X886135D02*
X878969D01*
G01X902419Y546173D02*
X906607D01*
G01X901246D02*
X901749D01*
G01X885544Y546127D02*
X884206D01*
G01X906607Y545352D02*
X901246D01*
G01X884206Y544788D02*
X885544D01*
G01X878969Y544198D02*
X877788D01*
G01X886135D02*
X878969D01*
G01X903424Y544040D02*
X901916D01*
G01X903256Y543220D02*
X902084D01*
G01X868969Y542032D02*
X878969D01*
G01X868969Y541245D02*
X878969D01*
G01Y539670D02*
X868969D01*
G01X902084Y538955D02*
X903256D01*
G01X878969Y538883D02*
X868969D01*
G01X901916Y538135D02*
X903424D01*
G01X903256Y536822D02*
X903927D01*
G01X901246D02*
X901916D01*
G01X878969Y536717D02*
X877788D01*
G01X886135D02*
X878969D01*
G01X885544Y536127D02*
X884206D01*
G01Y534788D02*
X885544D01*
G01X878969Y534198D02*
X877788D01*
G01X886135D02*
X878969D01*
G01X901916D02*
X901246D01*
G01X903927D02*
X903256D01*
G01X898733Y532885D02*
X906607D01*
G01X868969Y532032D02*
X878969D01*
G01X901916Y531901D02*
X898733D01*
G01X906607D02*
X902921D01*
G01X868969Y531245D02*
X878969D01*
G01Y529670D02*
X868969D01*
G01X878969Y528883D02*
X868969D01*
G01X902921Y527308D02*
X906607D01*
G01X898733D02*
X901916D01*
G01X878969Y526717D02*
X877788D01*
G01X886135D02*
X878969D01*
G01X906607Y526324D02*
X898733D01*
G01X885544Y526127D02*
X884206D01*
G01Y524788D02*
X885544D01*
G01X878969Y524198D02*
X877788D01*
G01X886135D02*
X878969D01*
G01X868969Y522032D02*
X878969D01*
G01X868969Y521245D02*
X878969D01*
G01X868969Y520457D02*
X878969D01*
G01X902084Y543220D02*
X901079Y543056D01*
G01X903256Y538955D02*
X904262Y539119D01*
G01X901916Y544040D02*
X901079Y543876D01*
G01X903424Y538135D02*
X904262Y538299D01*
G01X882877Y554198D02*
G03Y556717I1998J1260D01*
G01Y564198D02*
G03Y566717I1998J1260D01*
G01Y556717D02*
G03Y554198I1998J-1260D01*
G01Y566717D02*
G03Y564198I1998J-1260D01*
G01X905977Y588765D02*
G03I-7086J0D01*
G01X887973Y565430D02*
X887848Y565389D01*
G01Y565635D02*
X887973Y565676D01*
G01X901749Y558476D02*
X902586Y558804D01*
G01Y555359D02*
X902251Y555195D01*
G01X902586Y557984D02*
X902251Y557820D01*
G01X887680Y565512D02*
X887848Y565635D01*
G01X902251Y555195D02*
X902084Y555031D01*
G01X901414Y555523D02*
X901916Y556015D01*
G01X902251Y557820D02*
X902084Y557656D01*
G01X901414Y558148D02*
X901749Y558476D01*
G01X887848Y565389D02*
X887764Y565307D01*
G01X885544Y556127D02*
X886135Y556717D01*
G01X884206Y554788D02*
X883615Y554198D01*
G01X885544Y566127D02*
X886135Y566717D01*
G01X884206Y564788D02*
X883615Y564198D01*
G01X887555Y565348D02*
X887680Y565512D01*
G01X902084Y555031D02*
X901916Y554703D01*
G01X902084Y557656D02*
X901916Y557328D01*
G01X901246Y555031D02*
X901414Y555523D01*
G01X901246Y557656D02*
X901414Y558148D01*
G01X887764Y565307D02*
X887722Y565184D01*
G01X887513Y565143D02*
X887555Y565348D01*
G01X901916Y554703D02*
Y554375D01*
G01Y557328D02*
Y556835D01*
G01X901246Y556999D02*
Y557656D01*
G01Y554375D02*
Y555031D01*
G01Y552734D02*
Y553555D01*
G01X889481Y564404D02*
Y564158D01*
G01Y566496D02*
Y566250D01*
G01X888602Y565143D02*
Y564404D01*
G01X888350D02*
Y565184D01*
G01X887722D02*
Y564404D01*
G01X887513Y566250D02*
Y566496D01*
G01Y564158D02*
Y565143D01*
G01X886135Y556717D02*
Y554198D01*
G01Y566717D02*
Y564198D01*
G01X885544Y564788D02*
Y566127D01*
G01Y554788D02*
Y556127D01*
G01X884206Y564788D02*
Y566127D01*
G01Y554788D02*
Y556127D01*
G01X883615Y556717D02*
Y554198D01*
G01Y566717D02*
Y564198D01*
G01X882631Y556717D02*
Y554198D01*
G01Y566717D02*
Y564198D01*
G01X868969Y570457D02*
Y780300D01*
G01Y570457D02*
Y780300D01*
G01X888560Y565348D02*
X888602Y565143D01*
G01X901414Y556507D02*
X901246Y556999D01*
G01X901916Y554375D02*
X902084Y553883D01*
G01X901414D02*
X901246Y554375D01*
G01X888350Y565184D02*
X888308Y565307D01*
G01X901916Y556835D02*
X902084Y556507D01*
G01X888434Y565512D02*
X888560Y565348D01*
G01X884206Y566127D02*
X883615Y566717D01*
G01X886135Y564198D02*
X885544Y564788D01*
G01X902084Y556507D02*
X902251Y556343D01*
G01X901916Y556015D02*
X901414Y556507D01*
G01X902084Y553883D02*
X902419Y553555D01*
G01X901749D02*
X901414Y553883D01*
G01X888308Y565307D02*
X888225Y565389D01*
G01X884206Y556127D02*
X883615Y556717D01*
G01X886135Y554198D02*
X885544Y554788D01*
G01X887848Y566250D02*
X888141Y566004D01*
G01X887806D02*
X887513Y566250D01*
G01X888267Y565635D02*
X888434Y565512D01*
G01X902251Y556343D02*
X902586Y556179D01*
G01X888141Y565676D02*
X888267Y565635D01*
G01X888225Y565389D02*
X888099Y565430D01*
G01X868969Y570457D02*
X878969D01*
G01Y569670D02*
X868969D01*
G01X878969Y568883D02*
X868969D01*
G01X878969Y566717D02*
X877788D01*
G01X886135D02*
X878969D01*
G01X887513Y566496D02*
X889481D01*
G01Y566250D02*
X887848D01*
G01X885544Y566127D02*
X884206D01*
G01X888141Y566004D02*
X887806D01*
G01X887973Y565676D02*
X888141D01*
G01X888099Y565430D02*
X887973D01*
G01X884206Y564788D02*
X885544D01*
G01X887722Y564404D02*
X888350D01*
G01X888602D02*
X889481D01*
G01X878969Y564198D02*
X877788D01*
G01X886135D02*
X878969D01*
G01X889481Y564158D02*
X887513D01*
G01X868969Y562032D02*
X878969D01*
G01X868969Y561245D02*
X878969D01*
G01Y559670D02*
X868969D01*
G01X878969Y558883D02*
X868969D01*
G01X902586Y558804D02*
X906607D01*
G01Y557984D02*
X902586D01*
G01X878969Y556717D02*
X877788D01*
G01X886135D02*
X878969D01*
G01X902586Y556179D02*
X906607D01*
G01X885544Y556127D02*
X884206D01*
G01X906607Y555359D02*
X902586D01*
G01X884206Y554788D02*
X885544D01*
G01X878969Y554198D02*
X877788D01*
G01X886135D02*
X878969D01*
G01X902419Y553555D02*
X906607D01*
G01X901246D02*
X901749D01*
G01X906607Y552734D02*
X901246D01*
G01X922119Y612387D02*
X868969D01*
G01X903418Y674040D02*
G03I-6890J0D01*
G01X912276D02*
G03I-15748J0D01*
G01X905977Y761993D02*
G03I-7086J0D01*
G01X868969Y738371D02*
X922119D01*
G01X882877Y784040D02*
G03Y786560I1998J1260D01*
G01Y794040D02*
G03Y796560I1998J1260D01*
G01Y804040D02*
G03Y806560I1998J1260D01*
G01Y786560D02*
G03Y784040I1998J-1260D01*
G01Y796560D02*
G03Y794040I1998J-1260D01*
G01Y806560D02*
G03Y804040I1998J-1260D01*
G01X902726Y799007D02*
X903229Y799171D01*
G01X899543Y804585D02*
X899041Y804421D01*
G01X903229Y799171D02*
X903899Y799499D01*
G01X899041Y804421D02*
X898370Y804093D01*
G01X902726Y799828D02*
X903731Y800484D01*
G01X899543Y803765D02*
X898538Y803108D01*
G01X898370Y804093D02*
X897868Y803601D01*
G01X885544Y785969D02*
X886135Y786560D01*
G01X884206Y784631D02*
X883615Y784040D01*
G01X885544Y795969D02*
X886135Y796560D01*
G01X884206Y794631D02*
X883615Y794040D01*
G01X885544Y805969D02*
X886135Y806560D01*
G01X884206Y804631D02*
X883615Y804040D01*
G01X903731Y800484D02*
X904066Y800976D01*
G01X898538Y803108D02*
X898203Y802616D01*
G01X897868Y803601D02*
X897365Y802780D01*
G01X898203Y802616D02*
X898035Y801796D01*
G01X897365Y802780D02*
X897198Y801796D01*
G01D02*
X897365Y800812D01*
G01X898035Y801796D02*
X898203Y800976D01*
G01X902391Y797531D02*
Y794906D01*
G01X901721D02*
Y797531D01*
G01X901386Y792610D02*
Y788017D01*
G01X900381D02*
Y792610D01*
G01Y797531D02*
Y794906D01*
G01Y808030D02*
Y807702D01*
G01X899711D02*
Y808358D01*
G01Y806061D02*
Y806881D01*
G01Y794906D02*
Y797531D01*
G01X897198Y792610D02*
Y793594D01*
G01Y787032D02*
Y788017D01*
G01X886135Y786560D02*
Y784040D01*
G01Y796560D02*
Y794040D01*
G01Y806560D02*
Y804040D01*
G01X885544Y804631D02*
Y805969D01*
G01Y794631D02*
Y795969D01*
G01Y784631D02*
Y785969D01*
G01X884206Y804631D02*
Y805969D01*
G01Y794631D02*
Y795969D01*
G01Y784631D02*
Y785969D01*
G01X883615Y786560D02*
Y784040D01*
G01Y796560D02*
Y794040D01*
G01Y806560D02*
Y804040D01*
G01X882631Y786560D02*
Y784040D01*
G01Y796560D02*
Y794040D01*
G01Y806560D02*
Y804040D01*
G01X878969Y780300D02*
Y830300D01*
G01X877788D02*
Y780300D01*
G01X868969D02*
Y830300D01*
G01Y780300D02*
Y830300D01*
G01Y780300D02*
Y830300D01*
G01X900381Y807702D02*
X900548Y807209D01*
G01X899878D02*
X899711Y807702D01*
G01X897365Y800812D02*
X897868Y799992D01*
G01X904066Y802616D02*
X903731Y803108D01*
G01X898203Y800976D02*
X898538Y800484D01*
G01X886135Y804040D02*
X885544Y804631D01*
G01X884206Y805969D02*
X883615Y806560D01*
G01X884206Y795969D02*
X883615Y796560D01*
G01X886135Y794040D02*
X885544Y794631D01*
G01X884206Y785969D02*
X883615Y786560D01*
G01X886135Y784040D02*
X885544Y784631D01*
G01X900548Y807209D02*
X900883Y806881D01*
G01X900213D02*
X899878Y807209D01*
G01X897868Y799992D02*
X898370Y799499D01*
G01X903731Y803108D02*
X902726Y803765D01*
G01X898538Y800484D02*
X899543Y799828D01*
G01X903899Y804093D02*
X903229Y804421D01*
G01X898370Y799499D02*
X899041Y799171D01*
G01X903229Y804421D02*
X902726Y804585D01*
G01X899041Y799171D02*
X899543Y799007D01*
G01X902726Y804585D02*
X901889Y804749D01*
G01X899543Y799007D02*
X900381Y798843D01*
G01X902726Y803765D02*
X901721Y803929D01*
G01X899543Y799828D02*
X900548Y799664D01*
G01X900883Y806881D02*
X905072D01*
G01X899711D02*
X900213D01*
G01X878969Y806560D02*
X877788D01*
G01X886135D02*
X878969D01*
G01X905072Y806061D02*
X899711D01*
G01X885544Y805969D02*
X884206D01*
G01X901889Y804749D02*
X900381D01*
G01X884206Y804631D02*
X885544D01*
G01X878969Y804040D02*
X877788D01*
G01X886135D02*
X878969D01*
G01X901721Y803929D02*
X900548D01*
G01X868969Y801875D02*
X878969D01*
G01X868969Y801087D02*
X878969D01*
G01X900548Y799664D02*
X901721D01*
G01X878969Y799513D02*
X868969D01*
G01X900381Y798843D02*
X901889D01*
G01X878969Y798725D02*
X868969D01*
G01X901721Y797531D02*
X902391D01*
G01X899711D02*
X900381D01*
G01X878969Y796560D02*
X877788D01*
G01X886135D02*
X878969D01*
G01X885544Y795969D02*
X884206D01*
G01X902391Y794906D02*
X901721D01*
G01X900381D02*
X899711D01*
G01X884206Y794631D02*
X885544D01*
G01X878969Y794040D02*
X877788D01*
G01X886135D02*
X878969D01*
G01X897198Y793594D02*
X905072D01*
G01X900381Y792610D02*
X897198D01*
G01X905072D02*
X901386D01*
G01X868969Y791875D02*
X878969D01*
G01X868969Y791087D02*
X878969D01*
G01Y789513D02*
X868969D01*
G01X878969Y788725D02*
X868969D01*
G01X901386Y788017D02*
X905072D01*
G01X897198D02*
X900381D01*
G01X905072Y787032D02*
X897198D01*
G01X878969Y786560D02*
X877788D01*
G01X886135D02*
X878969D01*
G01X885544Y785969D02*
X884206D01*
G01Y784631D02*
X885544D01*
G01X878969Y784040D02*
X877788D01*
G01X886135D02*
X878969D01*
G01X868969Y781875D02*
X878969D01*
G01X868969Y781087D02*
X878969D01*
G01X868969Y780300D02*
X878969D01*
G01X900548Y803929D02*
X899543Y803765D01*
G01X901721Y799664D02*
X902726Y799828D01*
G01X900381Y804749D02*
X899543Y804585D01*
G01X901889Y798843D02*
X902726Y799007D01*
G01X882877Y814040D02*
G03Y816560I1998J1260D01*
G01Y824040D02*
G03Y826560I1998J1260D01*
G01Y816560D02*
G03Y814040I1998J-1260D01*
G01Y826560D02*
G03Y824040I1998J-1260D01*
G01X905977Y848607D02*
G03I-7086J0D01*
G01X887973Y825272D02*
X887848Y825231D01*
G01Y825477D02*
X887973Y825518D01*
G01X900213Y811803D02*
X901051Y812131D01*
G01X900213Y819184D02*
X901051Y819513D01*
G01Y808686D02*
X900716Y808522D01*
G01X901051Y811310D02*
X900716Y811146D01*
G01X901051Y816068D02*
X900716Y815904D01*
G01X901051Y818692D02*
X900716Y818528D01*
G01X887680Y825354D02*
X887848Y825477D01*
G01X900716Y808522D02*
X900548Y808358D01*
G01X899878Y808850D02*
X900381Y809342D01*
G01X900716Y811146D02*
X900548Y810982D01*
G01X899878Y811475D02*
X900213Y811803D01*
G01X900716Y815904D02*
X900548Y815740D01*
G01X899878Y816232D02*
X900381Y816724D01*
G01X900716Y818528D02*
X900548Y818364D01*
G01X899878Y818856D02*
X900213Y819184D01*
G01X887848Y825231D02*
X887764Y825149D01*
G01X885544Y815969D02*
X886135Y816560D01*
G01X884206Y814631D02*
X883615Y814040D01*
G01X885544Y825969D02*
X886135Y826560D01*
G01X884206Y824631D02*
X883615Y824040D01*
G01X887555Y825190D02*
X887680Y825354D01*
G01X900548Y808358D02*
X900381Y808030D01*
G01X900548Y810982D02*
X900381Y810654D01*
G01X900548Y815740D02*
X900381Y815412D01*
G01X900548Y818364D02*
X900381Y818036D01*
G01X899711Y808358D02*
X899878Y808850D01*
G01X899711Y810982D02*
X899878Y811475D01*
G01X899711Y815740D02*
X899878Y816232D01*
G01X899711Y818364D02*
X899878Y818856D01*
G01X887764Y825149D02*
X887722Y825026D01*
G01X887513Y824985D02*
X887555Y825190D01*
G01X888560D02*
X888602Y824985D01*
G01X900381Y810654D02*
Y810162D01*
G01Y815412D02*
Y815083D01*
G01Y818036D02*
Y817544D01*
G01X899711Y817708D02*
Y818364D01*
G01Y815083D02*
Y815740D01*
G01Y813443D02*
Y814263D01*
G01Y810326D02*
Y810982D01*
G01X889481Y826338D02*
Y826092D01*
G01Y824247D02*
Y824001D01*
G01X888602Y824985D02*
Y824247D01*
G01X888350D02*
Y825026D01*
G01X887722D02*
Y824247D01*
G01X887513Y826092D02*
Y826338D01*
G01Y824001D02*
Y824985D01*
G01X886135Y816560D02*
Y814040D01*
G01Y826560D02*
Y824040D01*
G01X885544Y824631D02*
Y825969D01*
G01Y814631D02*
Y815969D01*
G01X884206Y824631D02*
Y825969D01*
G01Y814631D02*
Y815969D01*
G01X883615Y816560D02*
Y814040D01*
G01Y826560D02*
Y824040D01*
G01X882631Y816560D02*
Y814040D01*
G01Y826560D02*
Y824040D01*
G01X868969Y830300D02*
Y951934D01*
G01Y830300D02*
Y951934D01*
G01X899878Y817216D02*
X899711Y817708D01*
G01X900381Y815083D02*
X900548Y814591D01*
G01X899878D02*
X899711Y815083D01*
G01X899878Y809834D02*
X899711Y810326D01*
G01X888350Y825026D02*
X888308Y825149D01*
G01X900381Y817544D02*
X900548Y817216D01*
G01X900381Y810162D02*
X900548Y809834D01*
G01X888434Y825354D02*
X888560Y825190D01*
G01X884206Y825969D02*
X883615Y826560D01*
G01X886135Y824040D02*
X885544Y824631D01*
G01X884206Y815969D02*
X883615Y816560D01*
G01X886135Y814040D02*
X885544Y814631D01*
G01X900548Y817216D02*
X900716Y817052D01*
G01X900381Y816724D02*
X899878Y817216D01*
G01X900548Y814591D02*
X900883Y814263D01*
G01X900213D02*
X899878Y814591D01*
G01X888308Y825149D02*
X888225Y825231D01*
G01X900548Y809834D02*
X900716Y809670D01*
G01X900381Y809342D02*
X899878Y809834D01*
G01X887848Y826092D02*
X888141Y825846D01*
G01X887806D02*
X887513Y826092D01*
G01X888267Y825477D02*
X888434Y825354D01*
G01X900716Y817052D02*
X901051Y816888D01*
G01X900716Y809670D02*
X901051Y809506D01*
G01X888141Y825518D02*
X888267Y825477D01*
G01X888225Y825231D02*
X888099Y825272D01*
G01X868969Y830300D02*
X878969D01*
G01Y829513D02*
X868969D01*
G01X878969Y828725D02*
X868969D01*
G01X878969Y826560D02*
X877788D01*
G01X886135D02*
X878969D01*
G01X887513Y826338D02*
X889481D01*
G01Y826092D02*
X887848D01*
G01X885544Y825969D02*
X884206D01*
G01X888141Y825846D02*
X887806D01*
G01X887973Y825518D02*
X888141D01*
G01X888099Y825272D02*
X887973D01*
G01X884206Y824631D02*
X885544D01*
G01X887722Y824247D02*
X888350D01*
G01X888602D02*
X889481D01*
G01X878969Y824040D02*
X877788D01*
G01X886135D02*
X878969D01*
G01X889481Y824001D02*
X887513D01*
G01X868969Y821875D02*
X878969D01*
G01X868969Y821087D02*
X878969D01*
G01X901051Y819513D02*
X905072D01*
G01X878969D02*
X868969D01*
G01X878969Y818725D02*
X868969D01*
G01X905072Y818692D02*
X901051D01*
G01Y816888D02*
X905072D01*
G01X878969Y816560D02*
X877788D01*
G01X886135D02*
X878969D01*
G01X905072Y816068D02*
X901051D01*
G01X885544Y815969D02*
X884206D01*
G01Y814631D02*
X885544D01*
G01X900883Y814263D02*
X905072D01*
G01X899711D02*
X900213D01*
G01X878969Y814040D02*
X877788D01*
G01X886135D02*
X878969D01*
G01X905072Y813443D02*
X899711D01*
G01X901051Y812131D02*
X905072D01*
G01X868969Y811875D02*
X878969D01*
G01X905072Y811310D02*
X901051D01*
G01X868969Y811087D02*
X878969D01*
G01Y809513D02*
X868969D01*
G01X901051Y809506D02*
X905072D01*
G01X878969Y808725D02*
X868969D01*
G01X905072Y808686D02*
X901051D01*
G01X922119Y872229D02*
X868969D01*
G01X886489Y949611D02*
G03X887080Y949020I591J0D01*
G01X886489Y954729D02*
G03X885898Y955320I-591J0D01*
G01X880387Y960753D02*
G03X880190Y960556I0J-197D01*
G01Y959217D02*
G03X880387Y959020I197J0D01*
G01Y957052D02*
G03X880190Y956855I0J-197D01*
G01Y955517D02*
G03X880387Y955320I197J0D01*
G01X866017Y964139D02*
G03Y951934I0J-6102D01*
G01X885471Y963115D02*
X882158Y960753D01*
G01X897709Y952918D02*
X899284Y955753D01*
G01X899678Y956461D02*
X899284Y955753D01*
G01X883024Y947052D02*
X880190Y953566D01*
G01X899284Y960320D02*
X897709Y963154D01*
G01X899284Y960320D02*
X899678Y959611D01*
G01X899284Y950083D02*
X897709Y951973D01*
G01X899284Y950083D02*
X899678Y949611D01*
G01X901353Y948430D02*
X901646Y948184D01*
G01X901311D02*
X901253Y948233D01*
G01D02*
X901018Y948430D01*
G01X882158Y960753D02*
X880387D01*
G01X901646Y959611D02*
X899678D01*
G01X899284Y959020D02*
X901253D01*
G01X880387D02*
X899284D01*
G01X901646D02*
X901253D01*
G01D02*
X899284D01*
G01Y957052D02*
X880387D01*
G01X901253D02*
X899284D01*
G01X901646D02*
X901253D01*
G01D02*
X899284D01*
G01X901646Y956461D02*
X899678D01*
G01X880387Y955320D02*
X885898D01*
G01X874875Y951934D02*
X880190D01*
G01X874875D02*
X866017D01*
G01X880190Y951894D02*
X874875D01*
G01X896528Y951868D02*
X880190D01*
G01X901646Y949611D02*
X899678D01*
G01X899284Y949020D02*
X901253D01*
G01X887080D02*
X899284D01*
G01X901646D02*
X901253D01*
G01D02*
X899284D01*
G01X901253Y948430D02*
X901353D01*
G01X901018D02*
X901253D01*
G01Y948184D02*
X901311D01*
G01X899678D02*
X901253D01*
G01X901646Y947938D02*
X901253D01*
G01D02*
X899678D01*
G01X899284Y947603D02*
X878812D01*
G01X899284Y947052D02*
X883024D01*
G01X901253D02*
X899284D01*
G01X901646D02*
X901253D01*
G01D02*
X899284D01*
G01X874875Y946855D02*
X899284D01*
G01X897709Y946461D02*
X899284D01*
G01X901646D02*
X899284D01*
G01X874875Y944847D02*
X901646D01*
G01X863064Y940910D02*
X905583D01*
G01X901646Y959020D02*
Y967052D01*
G01Y949020D02*
Y957052D01*
G01Y944847D02*
Y947052D01*
G01Y948184D02*
Y947938D01*
G01X901253Y949020D02*
Y947052D01*
G01Y959020D02*
Y957052D01*
G01X900505Y949020D02*
Y947052D01*
G01Y959020D02*
Y957052D01*
G01X899678Y947938D02*
Y948184D01*
G01X899284Y955753D02*
Y960320D01*
G01Y957052D02*
Y959020D01*
G01Y946461D02*
Y950083D01*
G01Y949020D02*
Y947052D01*
G01X897709Y946461D02*
Y969611D01*
G01X896528Y965049D02*
Y951868D01*
G01X886489Y954729D02*
Y949611D01*
G01X880387Y955320D02*
Y953114D01*
G01Y959020D02*
Y957052D01*
G01X880190Y966066D02*
Y951868D01*
G01Y965517D02*
Y951934D01*
G01X878812Y968469D02*
Y947603D01*
G01X876253Y965517D02*
Y951934D01*
G01X875465Y964926D02*
Y951934D01*
G01X874875Y944847D02*
Y971225D01*
G01X868969Y951934D02*
Y964139D01*
G01Y951934D02*
Y964139D01*
G01X866017Y951934D02*
Y964139D01*
G01X863064Y952706D02*
Y940910D01*
G01Y963367D02*
Y952706D01*
G01X886848Y967052D02*
G03X886258Y966461I1J-591D01*
G01X863064Y975162D02*
X905583D01*
G01X874875Y971225D02*
X901646D01*
G01X897709Y964493D02*
X899284Y966068D01*
G01X899678Y966461D02*
X899284Y966068D01*
G01X880190Y962328D02*
X883103Y969020D01*
G01X897709Y969611D02*
X899284D01*
G01X901646D02*
X899284D01*
G01X874875Y969217D02*
X899284D01*
G01Y969020D02*
X901253D01*
G01X899284D02*
X883103D01*
G01X901646D02*
X901253D01*
G01D02*
X899284D01*
G01Y968469D02*
X878812D01*
G01X899284Y967052D02*
X901253D01*
G01X886848D02*
X899284D01*
G01X901646D02*
X901253D01*
G01D02*
X899284D01*
G01X901646Y966461D02*
X899678D01*
G01X880190Y966066D02*
X874875D01*
G01X876253Y965517D02*
X880190D01*
G01X896528Y965049D02*
X880190D01*
G01X875465Y964926D02*
X876253D01*
G01X874875Y964139D02*
X866017D01*
G01X875465D02*
X874875D01*
G01X886258Y963115D02*
X885471D01*
G01X901646Y969020D02*
Y971225D01*
G01X901253Y969020D02*
Y967052D01*
G01X900505Y969020D02*
Y967052D01*
G01X899284Y966068D02*
Y969611D01*
G01Y969020D02*
Y967052D01*
G01X886258Y966461D02*
Y963115D01*
G01X868969Y964139D02*
Y1092603D01*
G01Y964139D02*
Y1092603D01*
G01X863064Y975162D02*
Y963367D01*
G01X886848Y1107721D02*
G03X886258Y1107131I0J-590D01*
G01X886489Y1090280D02*
G03X887080Y1089690I590J0D01*
G01X886489Y1095398D02*
G03X885898Y1095989I-591J0D01*
G01X880387Y1101422D02*
G03X880190Y1101225I0J-197D01*
G01Y1099887D02*
G03X880387Y1099690I197J0D01*
G01Y1097721D02*
G03X880190Y1097524I0J-197D01*
G01Y1096186D02*
G03X880387Y1095989I197J0D01*
G01X866017Y1104808D02*
G03Y1092603I0J-6103D01*
G01X874875Y1111894D02*
X901646D01*
G01X897709Y1110280D02*
X899284D01*
G01X901646D02*
X899284D01*
G01X874875Y1109887D02*
X899284D01*
G01Y1109690D02*
X901253D01*
G01X899284D02*
X883103D01*
G01X901646D02*
X901253D01*
G01D02*
X899284D01*
G01Y1109139D02*
X878812D01*
G01X899284Y1107721D02*
X901253D01*
G01X886848D02*
X899284D01*
G01X901646D02*
X901253D01*
G01D02*
X899284D01*
G01X901646Y1107131D02*
X899678D01*
G01X880190Y1106735D02*
X874875D01*
G01X876253Y1106186D02*
X880190D01*
G01X896528Y1105718D02*
X880190D01*
G01X875465Y1105595D02*
X876253D01*
G01X874875Y1104808D02*
X866017D01*
G01X875465D02*
X874875D01*
G01X886258Y1103784D02*
X885471D01*
G01X882158Y1101422D02*
X880387D01*
G01X901646Y1100280D02*
X899678D01*
G01X899284Y1099690D02*
X901253D01*
G01X880387D02*
X899284D01*
G01X901646D02*
X901253D01*
G01D02*
X899284D01*
G01Y1097721D02*
X880387D01*
G01X901253D02*
X899284D01*
G01X901646D02*
X901253D01*
G01D02*
X899284D01*
G01X901646Y1097131D02*
X899678D01*
G01X880387Y1095989D02*
X885898D01*
G01X874875Y1092603D02*
X880190D01*
G01X874875D02*
X866017D01*
G01X880190Y1092564D02*
X874875D01*
G01X896528Y1092537D02*
X880190D01*
G01X901646Y1090280D02*
X899678D01*
G01X899284Y1089690D02*
X901253D01*
G01X887080D02*
X899284D01*
G01X901646D02*
X901253D01*
G01D02*
X899284D01*
G01X901253Y1089099D02*
X901353D01*
G01X901018D02*
X901253D01*
G01Y1088853D02*
X901311D01*
G01X899678D02*
X901253D01*
G01X901646Y1088607D02*
X901253D01*
G01D02*
X899678D01*
G01X899284Y1088272D02*
X878812D01*
G01X899284Y1087721D02*
X883024D01*
G01X901253D02*
X899284D01*
G01X901646D02*
X901253D01*
G01D02*
X899284D01*
G01X874875Y1087524D02*
X899284D01*
G01X897709Y1087131D02*
X899284D01*
G01X901646D02*
X899284D01*
G01X874875Y1085517D02*
X901646D01*
G01X863064Y1081580D02*
X905583D01*
G01X883024Y1087721D02*
X880190Y1094235D01*
G01X899284Y1100989D02*
X897709Y1103824D01*
G01X899284Y1100989D02*
X899678Y1100280D01*
G01X899284Y1090753D02*
X897709Y1092643D01*
G01X899284Y1090753D02*
X899678Y1090280D01*
G01X901353Y1089099D02*
X901646Y1088853D01*
G01X901311D02*
X901253Y1088902D01*
G01D02*
X901018Y1089099D01*
G01X885471Y1103784D02*
X882158Y1101422D01*
G01X897709Y1105162D02*
X899284Y1106737D01*
G01X899678Y1107131D02*
X899284Y1106737D01*
G01X897709Y1093587D02*
X899284Y1096422D01*
G01X899678Y1097131D02*
X899284Y1096422D01*
G01X880190Y1102997D02*
X883103Y1109690D01*
G01X901646D02*
Y1111894D01*
G01Y1099690D02*
Y1107721D01*
G01Y1089690D02*
Y1097721D01*
G01Y1085517D02*
Y1087721D01*
G01Y1088853D02*
Y1088607D01*
G01X901253Y1089690D02*
Y1087721D01*
G01Y1099690D02*
Y1097721D01*
G01Y1109690D02*
Y1107721D01*
G01X900505Y1089690D02*
Y1087721D01*
G01Y1099690D02*
Y1097721D01*
G01Y1109690D02*
Y1107721D01*
G01X899678Y1088607D02*
Y1088853D01*
G01X899284Y1106737D02*
Y1110280D01*
G01Y1096422D02*
Y1100989D01*
G01Y1097721D02*
Y1099690D01*
G01Y1087131D02*
Y1090753D01*
G01Y1089690D02*
Y1087721D01*
G01Y1109690D02*
Y1107721D01*
G01X897709Y1087131D02*
Y1110280D01*
G01X896528Y1105718D02*
Y1092537D01*
G01X886489Y1095398D02*
Y1090280D01*
G01X886258Y1107131D02*
Y1103784D01*
G01X880387Y1095989D02*
Y1093783D01*
G01Y1099690D02*
Y1097721D01*
G01X880190Y1106186D02*
Y1092603D01*
G01Y1106735D02*
Y1092537D01*
G01X878812Y1109139D02*
Y1088272D01*
G01X876253Y1106186D02*
Y1092603D01*
G01X875465Y1105595D02*
Y1092603D01*
G01X874875Y1085517D02*
Y1111894D01*
G01X868969Y1104808D02*
Y1226442D01*
G01Y1104808D02*
Y1226442D01*
G01Y1092603D02*
Y1104808D01*
G01Y1092603D02*
Y1104808D01*
G01X866017Y1092603D02*
Y1104808D01*
G01X863064Y1093375D02*
Y1081580D01*
G01Y1104036D02*
Y1093375D01*
G01Y1115831D02*
Y1104036D01*
G01Y1115831D02*
X905583D01*
G01X905977Y1208135D02*
G03I-7086J0D01*
G01X868969Y1184513D02*
X922119D01*
G01X882877Y1230182D02*
G03Y1232702I1998J1260D01*
G01Y1240182D02*
G03Y1242702I1998J1260D01*
G01Y1250182D02*
G03Y1252702I1998J1260D01*
G01Y1260182D02*
G03Y1262702I1998J1260D01*
G01Y1232702D02*
G03Y1230182I1998J-1260D01*
G01Y1242702D02*
G03Y1240182I1998J-1260D01*
G01Y1252702D02*
G03Y1250182I1998J-1260D01*
G01Y1262702D02*
G03Y1260182I1998J-1260D01*
G01X868969Y1268017D02*
X878969D01*
G01X868969Y1267229D02*
X878969D01*
G01Y1265654D02*
X868969D01*
G01X878969Y1264867D02*
X868969D01*
G01X878969Y1262702D02*
X877788D01*
G01X886135D02*
X878969D01*
G01X885544Y1262111D02*
X884206D01*
G01X898964Y1260891D02*
X902985D01*
G01X884206Y1260772D02*
X885544D01*
G01X878969Y1260182D02*
X877788D01*
G01X886135D02*
X878969D01*
G01X902985Y1260070D02*
X898964D01*
G01Y1258266D02*
X902985D01*
G01X868969Y1258017D02*
X878969D01*
G01X902985Y1257446D02*
X898964D01*
G01X868969Y1257229D02*
X878969D01*
G01Y1255654D02*
X868969D01*
G01X898797Y1255641D02*
X902985D01*
G01X897624D02*
X898127D01*
G01X878969Y1254867D02*
X868969D01*
G01X902985Y1254821D02*
X897624D01*
G01X898964Y1253509D02*
X902985D01*
G01X878969Y1252702D02*
X877788D01*
G01X886135D02*
X878969D01*
G01X902985Y1252688D02*
X898964D01*
G01X885544Y1252111D02*
X884206D01*
G01X898964Y1250884D02*
X902985D01*
G01X884206Y1250772D02*
X885544D01*
G01X878969Y1250182D02*
X877788D01*
G01X886135D02*
X878969D01*
G01X902985Y1250064D02*
X898964D01*
G01X898797Y1248259D02*
X902985D01*
G01X897624D02*
X898127D01*
G01X868969Y1248017D02*
X878969D01*
G01X902985Y1247439D02*
X897624D01*
G01X868969Y1247229D02*
X878969D01*
G01X899802Y1246127D02*
X898294D01*
G01X878969Y1245654D02*
X868969D01*
G01X899634Y1245307D02*
X898462D01*
G01X878969Y1244867D02*
X868969D01*
G01X878969Y1242702D02*
X877788D01*
G01X886135D02*
X878969D01*
G01X885544Y1242111D02*
X884206D01*
G01X898462Y1241041D02*
X899634D01*
G01X884206Y1240772D02*
X885544D01*
G01X898294Y1240221D02*
X899802D01*
G01X878969Y1240182D02*
X877788D01*
G01X886135D02*
X878969D01*
G01X899634Y1238909D02*
X900305D01*
G01X897624D02*
X898294D01*
G01X868969Y1238017D02*
X878969D01*
G01X868969Y1237229D02*
X878969D01*
G01X898294Y1236284D02*
X897624D01*
G01X900305D02*
X899634D01*
G01X878969Y1235654D02*
X868969D01*
G01X898462Y1245307D02*
X897456Y1245143D01*
G01X899634Y1241041D02*
X900640Y1241206D01*
G01X898294Y1246127D02*
X897456Y1245963D01*
G01X899802Y1240221D02*
X900640Y1240385D01*
G01X901645Y1244486D02*
X900640Y1245143D01*
G01X896451Y1241862D02*
X897456Y1241206D01*
G01X898629Y1258430D02*
X898964Y1258266D01*
G01X898629Y1251048D02*
X898964Y1250884D01*
G01X901812Y1245471D02*
X901142Y1245799D01*
G01X896284Y1240877D02*
X896954Y1240549D01*
G01X901142Y1245799D02*
X900640Y1245963D01*
G01X896954Y1240549D02*
X897456Y1240385D01*
G01X900640Y1245963D02*
X899802Y1246127D01*
G01X897456Y1240385D02*
X898294Y1240221D01*
G01X900640Y1245143D02*
X899634Y1245307D01*
G01X897456Y1241206D02*
X898462Y1241041D01*
G01X895111Y1234972D02*
X902985D01*
G01X878969Y1234867D02*
X868969D01*
G01X898294Y1233988D02*
X895111D01*
G01X902985D02*
X899299D01*
G01X878969Y1232702D02*
X877788D01*
G01X886135D02*
X878969D01*
G01X885544Y1232111D02*
X884206D01*
G01Y1230772D02*
X885544D01*
G01X878969Y1230182D02*
X877788D01*
G01X886135D02*
X878969D01*
G01X899299Y1229394D02*
X902985D01*
G01X895111D02*
X898294D01*
G01X902985Y1228410D02*
X895111D01*
G01X868969Y1228017D02*
X878969D01*
G01X868969Y1227229D02*
X878969D01*
G01X868969Y1226442D02*
X878969D01*
G01X884206Y1262111D02*
X883615Y1262702D01*
G01X886135Y1260182D02*
X885544Y1260772D01*
G01X884206Y1252111D02*
X883615Y1252702D01*
G01X886135Y1250182D02*
X885544Y1250772D01*
G01X884206Y1242111D02*
X883615Y1242702D01*
G01X886135Y1240182D02*
X885544Y1240772D01*
G01X886135Y1230182D02*
X885544Y1230772D01*
G01X884206Y1232111D02*
X883615Y1232702D01*
G01X898462Y1258594D02*
X898629Y1258430D01*
G01X898294Y1258102D02*
X897792Y1258594D01*
G01X898462Y1255969D02*
X898797Y1255641D01*
G01X898127D02*
X897792Y1255969D01*
G01X898462Y1251212D02*
X898629Y1251048D01*
G01X898294Y1250720D02*
X897792Y1251212D01*
G01X902315Y1244978D02*
X901812Y1245471D01*
G01X898462Y1248587D02*
X898797Y1248259D01*
G01X898127D02*
X897792Y1248587D01*
G01X895781Y1241370D02*
X896284Y1240877D01*
G01X897792Y1258594D02*
X897624Y1259086D01*
G01X898294Y1256461D02*
X898462Y1255969D01*
G01X897792D02*
X897624Y1256461D01*
G01X897792Y1251212D02*
X897624Y1251704D01*
G01X898294Y1249080D02*
X898462Y1248587D01*
G01X897792D02*
X897624Y1249080D01*
G01X898294Y1258922D02*
X898462Y1258594D01*
G01X898294Y1251540D02*
X898462Y1251212D01*
G01X902818Y1244158D02*
X902315Y1244978D01*
G01X895279Y1242190D02*
X895781Y1241370D01*
G01X901980Y1243994D02*
X901645Y1244486D01*
G01X896116Y1242354D02*
X896451Y1241862D01*
G01X902985Y1243174D02*
X902818Y1244158D01*
G01X895111Y1243174D02*
X895279Y1242190D01*
G01X902147Y1243174D02*
X901980Y1243994D01*
G01X895949Y1243174D02*
X896116Y1242354D01*
G01X901980D02*
X902147Y1243174D01*
G01X896116Y1243994D02*
X895949Y1243174D01*
G01X902818Y1242190D02*
X902985Y1243174D01*
G01X895279Y1244158D02*
X895111Y1243174D01*
G01X902985Y1229394D02*
Y1228410D01*
G01Y1234972D02*
Y1233988D01*
G01Y1250884D02*
Y1250064D01*
G01Y1248259D02*
Y1247439D01*
G01Y1253509D02*
Y1252688D01*
G01Y1255641D02*
Y1254821D01*
G01Y1258266D02*
Y1257446D01*
G01Y1260891D02*
Y1260070D01*
G01X900305Y1238909D02*
Y1236284D01*
G01X899634D02*
Y1238909D01*
G01X899299Y1233988D02*
Y1229394D01*
G01X898294D02*
Y1233988D01*
G01Y1238909D02*
Y1236284D01*
G01Y1249408D02*
Y1249080D01*
G01Y1252032D02*
Y1251540D01*
G01Y1256789D02*
Y1256461D01*
G01Y1259414D02*
Y1258922D01*
G01X897624Y1259086D02*
Y1259742D01*
G01Y1256461D02*
Y1257118D01*
G01Y1254821D02*
Y1255641D01*
G01Y1251704D02*
Y1252360D01*
G01Y1249080D02*
Y1249736D01*
G01Y1247439D02*
Y1248259D01*
G01Y1236284D02*
Y1238909D01*
G01X895111Y1233988D02*
Y1234972D01*
G01Y1228410D02*
Y1229394D01*
G01X886135Y1232702D02*
Y1230182D01*
G01Y1242702D02*
Y1240182D01*
G01Y1252702D02*
Y1250182D01*
G01Y1262702D02*
Y1260182D01*
G01X885544Y1260772D02*
Y1262111D01*
G01Y1250772D02*
Y1252111D01*
G01Y1240772D02*
Y1242111D01*
G01Y1230772D02*
Y1232111D01*
G01X884206Y1260772D02*
Y1262111D01*
G01Y1250772D02*
Y1252111D01*
G01Y1240772D02*
Y1242111D01*
G01Y1230772D02*
Y1232111D01*
G01X883615Y1232702D02*
Y1230182D01*
G01Y1242702D02*
Y1240182D01*
G01Y1252702D02*
Y1250182D01*
G01Y1262702D02*
Y1260182D01*
G01X882631Y1232702D02*
Y1230182D01*
G01Y1242702D02*
Y1240182D01*
G01Y1252702D02*
Y1250182D01*
G01Y1262702D02*
Y1260182D01*
G01X878969Y1226442D02*
Y1276442D01*
G01X877788D02*
Y1226442D01*
G01X868969D02*
Y1276442D01*
G01Y1226442D02*
Y1276442D01*
G01Y1226442D02*
Y1276442D01*
G01X901645Y1241862D02*
X901980Y1242354D01*
G01X896451Y1244486D02*
X896116Y1243994D01*
G01X902315Y1241370D02*
X902818Y1242190D01*
G01X895781Y1244978D02*
X895279Y1244158D01*
G01X898462Y1249736D02*
X898294Y1249408D01*
G01X898462Y1252360D02*
X898294Y1252032D01*
G01X898462Y1257118D02*
X898294Y1256789D01*
G01X898462Y1259742D02*
X898294Y1259414D01*
G01X897624Y1249736D02*
X897792Y1250228D01*
G01X897624Y1252360D02*
X897792Y1252852D01*
G01X897624Y1257118D02*
X897792Y1257610D01*
G01X897624Y1259742D02*
X897792Y1260234D01*
G01X900640Y1240385D02*
X901142Y1240549D01*
G01X897456Y1245963D02*
X896954Y1245799D01*
G01X898127Y1253181D02*
X898964Y1253509D01*
G01X898127Y1260562D02*
X898964Y1260891D01*
G01X901142Y1240549D02*
X901812Y1240877D01*
G01X896954Y1245799D02*
X896284Y1245471D01*
G01X898964Y1250064D02*
X898629Y1249900D01*
G01X898964Y1252688D02*
X898629Y1252524D01*
G01X898964Y1257446D02*
X898629Y1257282D01*
G01X898964Y1260070D02*
X898629Y1259906D01*
G01X900640Y1241206D02*
X901645Y1241862D01*
G01X897456Y1245143D02*
X896451Y1244486D01*
G01X901812Y1240877D02*
X902315Y1241370D01*
G01X896284Y1245471D02*
X895781Y1244978D01*
G01X898629Y1249900D02*
X898462Y1249736D01*
G01X897792Y1250228D02*
X898294Y1250720D01*
G01X898629Y1252524D02*
X898462Y1252360D01*
G01X897792Y1252852D02*
X898127Y1253181D01*
G01X898629Y1257282D02*
X898462Y1257118D01*
G01X897792Y1257610D02*
X898294Y1258102D01*
G01X898629Y1259906D02*
X898462Y1259742D01*
G01X897792Y1260234D02*
X898127Y1260562D01*
G01X885544Y1232111D02*
X886135Y1232702D01*
G01X884206Y1230772D02*
X883615Y1230182D01*
G01X885544Y1242111D02*
X886135Y1242702D01*
G01X884206Y1240772D02*
X883615Y1240182D01*
G01X885544Y1252111D02*
X886135Y1252702D01*
G01X884206Y1250772D02*
X883615Y1250182D01*
G01X885544Y1262111D02*
X886135Y1262702D01*
G01X884206Y1260772D02*
X883615Y1260182D01*
G01X882877Y1270182D02*
G03Y1272702I1998J1260D01*
G01D02*
G03Y1270182I1998J-1260D01*
G01X905977Y1294749D02*
G03I-7086J0D01*
G01X922119Y1318371D02*
X868969D01*
G01X888141Y1271660D02*
X888267Y1271619D01*
G01X888225Y1271373D02*
X888099Y1271414D01*
G01X868969Y1276442D02*
X878969D01*
G01Y1275654D02*
X868969D01*
G01X878969Y1274867D02*
X868969D01*
G01X878969Y1272702D02*
X877788D01*
G01X886135D02*
X878969D01*
G01X887513Y1272480D02*
X889481D01*
G01Y1272234D02*
X887848D01*
G01X885544Y1272111D02*
X884206D01*
G01X888141Y1271988D02*
X887806D01*
G01X887973Y1271660D02*
X888141D01*
G01X888099Y1271414D02*
X887973D01*
G01X884206Y1270772D02*
X885544D01*
G01X887722Y1270389D02*
X888350D01*
G01X888602D02*
X889481D01*
G01X878969Y1270182D02*
X877788D01*
G01X886135D02*
X878969D01*
G01X889481Y1270143D02*
X887513D01*
G01X888267Y1271619D02*
X888434Y1271496D01*
G01D02*
X888560Y1271332D01*
G01X884206Y1272111D02*
X883615Y1272702D01*
G01X886135Y1270182D02*
X885544Y1270772D01*
G01X888308Y1271291D02*
X888225Y1271373D01*
G01X887848Y1272234D02*
X888141Y1271988D01*
G01X887806D02*
X887513Y1272234D01*
G01X888350Y1271168D02*
X888308Y1271291D01*
G01X888560Y1271332D02*
X888602Y1271127D01*
G01X887513D02*
X887555Y1271332D01*
G01X889481Y1270389D02*
Y1270143D01*
G01Y1272480D02*
Y1272234D01*
G01X888602Y1271127D02*
Y1270389D01*
G01X888350D02*
Y1271168D01*
G01X887722D02*
Y1270389D01*
G01X887513Y1272234D02*
Y1272480D01*
G01Y1270143D02*
Y1271127D01*
G01X886135Y1272702D02*
Y1270182D01*
G01X885544Y1270772D02*
Y1272111D01*
G01X884206Y1270772D02*
Y1272111D01*
G01X883615Y1272702D02*
Y1270182D01*
G01X882631Y1272702D02*
Y1270182D01*
G01X868969Y1276442D02*
Y1486284D01*
G01Y1276442D02*
Y1486284D01*
G01X887764Y1271291D02*
X887722Y1271168D01*
G01X887973Y1271414D02*
X887848Y1271373D01*
G01Y1271619D02*
X887973Y1271660D01*
G01X887680Y1271496D02*
X887848Y1271619D01*
G01Y1271373D02*
X887764Y1271291D01*
G01X885544Y1272111D02*
X886135Y1272702D01*
G01X884206Y1270772D02*
X883615Y1270182D01*
G01X887555Y1271332D02*
X887680Y1271496D01*
G01X902434Y1382702D02*
G03I-15748J0D01*
G01X893576D02*
G03I-6890J0D01*
G01X905977Y1467977D02*
G03I-7086J0D01*
G01X868969Y1444355D02*
X922119D01*
G01X882877Y1490024D02*
G03Y1492544I1998J1260D01*
G01Y1500024D02*
G03Y1502544I1998J1260D01*
G01Y1510024D02*
G03Y1512544I1998J1260D01*
G01Y1520024D02*
G03Y1522544I1998J1260D01*
G01Y1492544D02*
G03Y1490024I1998J-1260D01*
G01Y1502544D02*
G03Y1500024I1998J-1260D01*
G01Y1512544D02*
G03Y1510024I1998J-1260D01*
G01Y1522544D02*
G03Y1520024I1998J-1260D01*
G01X900562Y1523729D02*
X904583D01*
G01Y1522909D02*
X900562D01*
G01X878969Y1522544D02*
X877788D01*
G01X886135D02*
X878969D01*
G01X885544Y1521954D02*
X884206D01*
G01X900395Y1521105D02*
X904583D01*
G01X899222D02*
X899725D01*
G01X884206Y1520615D02*
X885544D01*
G01X904583Y1520285D02*
X899222D01*
G01X878969Y1520024D02*
X877788D01*
G01X886135D02*
X878969D01*
G01X900562Y1518972D02*
X904583D01*
G01Y1518152D02*
X900562D01*
G01X868969Y1517859D02*
X878969D01*
G01X868969Y1517072D02*
X878969D01*
G01X900562Y1516348D02*
X904583D01*
G01Y1515527D02*
X900562D01*
G01X878969Y1515497D02*
X868969D01*
G01X878969Y1514709D02*
X868969D01*
G01X900395Y1513723D02*
X904583D01*
G01X899222D02*
X899725D01*
G01X904583Y1512903D02*
X899222D01*
G01X878969Y1512544D02*
X877788D01*
G01X886135D02*
X878969D01*
G01X885544Y1511954D02*
X884206D01*
G01X901400Y1511590D02*
X899892D01*
G01X901232Y1510770D02*
X900060D01*
G01X884206Y1510615D02*
X885544D01*
G01X878969Y1510024D02*
X877788D01*
G01X886135D02*
X878969D01*
G01X868969Y1507859D02*
X878969D01*
G01X868969Y1507072D02*
X878969D01*
G01X900060Y1506505D02*
X901232D01*
G01X899892Y1505685D02*
X901400D01*
G01X878969Y1505497D02*
X868969D01*
G01X878969Y1504709D02*
X868969D01*
G01X901232Y1504372D02*
X901902D01*
G01X899222D02*
X899892D01*
G01X878969Y1502544D02*
X877788D01*
G01X886135D02*
X878969D01*
G01X885544Y1501954D02*
X884206D01*
G01X901902Y1501748D02*
X901232D01*
G01X899892D02*
X899222D01*
G01X884206Y1500615D02*
X885544D01*
G01X896709Y1500435D02*
X904583D01*
G01X878969Y1500024D02*
X877788D01*
G01X886135D02*
X878969D01*
G01X900060Y1510770D02*
X899054Y1510606D01*
G01X901232Y1506505D02*
X902238Y1506669D01*
G01X899892Y1511590D02*
X899054Y1511426D01*
G01X901400Y1505685D02*
X902238Y1505849D01*
G01X900227Y1523893D02*
X900562Y1523729D01*
G01X900227Y1516512D02*
X900562Y1516348D01*
G01X903410Y1510934D02*
X902740Y1511262D01*
G01D02*
X902238Y1511426D01*
G01X898552Y1506013D02*
X899054Y1505849D01*
G01X902238Y1511426D02*
X901400Y1511590D01*
G01X899054Y1505849D02*
X899892Y1505685D01*
G01X902238Y1510606D02*
X901232Y1510770D01*
G01X899054Y1506669D02*
X900060Y1506505D01*
G01X899892Y1499451D02*
X896709D01*
G01X904583D02*
X900897D01*
G01X868969Y1497859D02*
X878969D01*
G01X868969Y1497072D02*
X878969D01*
G01Y1495497D02*
X868969D01*
G01X900897Y1494858D02*
X904583D01*
G01X896709D02*
X899892D01*
G01X878969Y1494709D02*
X868969D01*
G01X904583Y1493874D02*
X896709D01*
G01X878969Y1492544D02*
X877788D01*
G01X886135D02*
X878969D01*
G01X885544Y1491954D02*
X884206D01*
G01Y1490615D02*
X885544D01*
G01X878969Y1490024D02*
X877788D01*
G01X886135D02*
X878969D01*
G01X868969Y1487859D02*
X878969D01*
G01X868969Y1487072D02*
X878969D01*
G01X868969Y1486284D02*
X878969D01*
G01X903243Y1509950D02*
X902238Y1510606D01*
G01X898049Y1507325D02*
X899054Y1506669D01*
G01X897882Y1506341D02*
X898552Y1506013D01*
G01X884206Y1521954D02*
X883615Y1522544D01*
G01X886135Y1520024D02*
X885544Y1520615D01*
G01X884206Y1511954D02*
X883615Y1512544D01*
G01X886135Y1510024D02*
X885544Y1510615D01*
G01X884206Y1501954D02*
X883615Y1502544D01*
G01X886135Y1500024D02*
X885544Y1500615D01*
G01X884206Y1491954D02*
X883615Y1492544D01*
G01X886135Y1490024D02*
X885544Y1490615D01*
G01X900060Y1524058D02*
X900227Y1523893D01*
G01X899892Y1523565D02*
X899389Y1524058D01*
G01X900060Y1521433D02*
X900395Y1521105D01*
G01X899725D02*
X899389Y1521433D01*
G01X900060Y1516676D02*
X900227Y1516512D01*
G01X899892Y1516183D02*
X899389Y1516676D01*
G01X903913Y1510442D02*
X903410Y1510934D01*
G01X900060Y1514051D02*
X900395Y1513723D01*
G01X899725D02*
X899389Y1514051D01*
G01X897379Y1506833D02*
X897882Y1506341D01*
G01X903578Y1509458D02*
X903243Y1509950D01*
G01X897714Y1507817D02*
X898049Y1507325D01*
G01X899892Y1524386D02*
X900060Y1524058D01*
G01X899892Y1517004D02*
X900060Y1516676D01*
G01X896876Y1507653D02*
X897379Y1506833D01*
G01X899389Y1524058D02*
X899222Y1524550D01*
G01X899892Y1521925D02*
X900060Y1521433D01*
G01X899389D02*
X899222Y1521925D01*
G01X899389Y1516676D02*
X899222Y1517168D01*
G01X899892Y1514543D02*
X900060Y1514051D01*
G01X899389D02*
X899222Y1514543D01*
G01X896709Y1508638D02*
X896876Y1507653D01*
G01X903745Y1508638D02*
X903578Y1509458D01*
G01X897547Y1508638D02*
X897714Y1507817D01*
G01X901902Y1504372D02*
Y1501748D01*
G01X901232D02*
Y1504372D01*
G01X900897Y1499451D02*
Y1494858D01*
G01X899892D02*
Y1499451D01*
G01Y1504372D02*
Y1501748D01*
G01Y1514871D02*
Y1514543D01*
G01Y1517496D02*
Y1517004D01*
G01Y1522253D02*
Y1521925D01*
G01X899222D02*
Y1522581D01*
G01Y1520285D02*
Y1521105D01*
G01Y1517168D02*
Y1517824D01*
G01Y1514543D02*
Y1515199D01*
G01Y1512903D02*
Y1513723D01*
G01Y1501748D02*
Y1504372D01*
G01X896709Y1499451D02*
Y1500435D01*
G01Y1493874D02*
Y1494858D01*
G01X886135Y1492544D02*
Y1490024D01*
G01Y1502544D02*
Y1500024D01*
G01Y1512544D02*
Y1510024D01*
G01Y1522544D02*
Y1520024D01*
G01X885544Y1520615D02*
Y1521954D01*
G01Y1510615D02*
Y1511954D01*
G01Y1500615D02*
Y1501954D01*
G01Y1490615D02*
Y1491954D01*
G01X884206Y1520615D02*
Y1521954D01*
G01Y1510615D02*
Y1511954D01*
G01Y1500615D02*
Y1501954D01*
G01Y1490615D02*
Y1491954D01*
G01X883615Y1492544D02*
Y1490024D01*
G01Y1502544D02*
Y1500024D01*
G01Y1512544D02*
Y1510024D01*
G01Y1522544D02*
Y1520024D01*
G01X882631Y1492544D02*
Y1490024D01*
G01Y1502544D02*
Y1500024D01*
G01Y1512544D02*
Y1510024D01*
G01Y1522544D02*
Y1520024D01*
G01X878969Y1486284D02*
Y1536284D01*
G01X877788D02*
Y1486284D01*
G01X868969D02*
Y1536284D01*
G01Y1486284D02*
Y1536284D01*
G01Y1486284D02*
Y1536284D01*
G01X903578Y1507817D02*
X903745Y1508638D01*
G01X897714Y1509458D02*
X897547Y1508638D01*
G01X896876Y1509622D02*
X896709Y1508638D01*
G01X899222Y1515199D02*
X899389Y1515691D01*
G01X899222Y1517824D02*
X899389Y1518316D01*
G01X899222Y1522581D02*
X899389Y1523073D01*
G01X903243Y1507325D02*
X903578Y1507817D01*
G01X897379Y1510442D02*
X896876Y1509622D01*
G01X900060Y1515199D02*
X899892Y1514871D01*
G01X900060Y1517824D02*
X899892Y1517496D01*
G01X900060Y1522581D02*
X899892Y1522253D01*
G01X903410Y1506341D02*
X903913Y1506833D01*
G01X885544Y1491954D02*
X886135Y1492544D01*
G01X884206Y1490615D02*
X883615Y1490024D01*
G01X898049Y1509950D02*
X897714Y1509458D01*
G01X902238Y1506669D02*
X903243Y1507325D01*
G01X899054Y1510606D02*
X898049Y1509950D01*
G01X897882Y1510934D02*
X897379Y1510442D01*
G01X900227Y1515363D02*
X900060Y1515199D01*
G01X899389Y1515691D02*
X899892Y1516183D01*
G01X900227Y1517988D02*
X900060Y1517824D01*
G01X899389Y1518316D02*
X899725Y1518644D01*
G01X900227Y1522745D02*
X900060Y1522581D01*
G01X899389Y1523073D02*
X899892Y1523565D01*
G01X885544Y1501954D02*
X886135Y1502544D01*
G01X884206Y1500615D02*
X883615Y1500024D01*
G01X885544Y1511954D02*
X886135Y1512544D01*
G01X884206Y1510615D02*
X883615Y1510024D01*
G01X885544Y1521954D02*
X886135Y1522544D01*
G01X884206Y1520615D02*
X883615Y1520024D01*
G01X902238Y1505849D02*
X902740Y1506013D01*
G01X899054Y1511426D02*
X898552Y1511262D01*
G01X899725Y1518644D02*
X900562Y1518972D01*
G01X902740Y1506013D02*
X903410Y1506341D01*
G01X898552Y1511262D02*
X897882Y1510934D01*
G01X900562Y1515527D02*
X900227Y1515363D01*
G01X900562Y1518152D02*
X900227Y1517988D01*
G01X900562Y1522909D02*
X900227Y1522745D01*
G01X905977Y1554591D02*
G03I-7086J0D01*
G01X882877Y1530024D02*
G03Y1532544I1998J1260D01*
G01D02*
G03Y1530024I1998J-1260D01*
G01X868969Y1536284D02*
X878969D01*
G01Y1535497D02*
X868969D01*
G01X878969Y1534709D02*
X868969D01*
G01X878969Y1532544D02*
X877788D01*
G01X886135D02*
X878969D01*
G01X887513Y1532323D02*
X889481D01*
G01Y1532077D02*
X887848D01*
G01X885544Y1531954D02*
X884206D01*
G01X888141Y1531830D02*
X887806D01*
G01X887973Y1531502D02*
X888141D01*
G01X888099Y1531256D02*
X887973D01*
G01X884206Y1530615D02*
X885544D01*
G01X887722Y1530231D02*
X888350D01*
G01X888602D02*
X889481D01*
G01X878969Y1530024D02*
X877788D01*
G01X886135D02*
X878969D01*
G01X889481Y1529985D02*
X887513D01*
G01X868969Y1527859D02*
X878969D01*
G01X868969Y1527072D02*
X878969D01*
G01X900562Y1526354D02*
X904583D01*
G01Y1525534D02*
X900562D01*
G01X878969Y1525497D02*
X868969D01*
G01X878969Y1524709D02*
X868969D01*
G01X888141Y1531502D02*
X888267Y1531461D01*
G01X888225Y1531215D02*
X888099Y1531256D01*
G01X888267Y1531461D02*
X888434Y1531338D01*
G01X884206Y1531954D02*
X883615Y1532544D01*
G01X886135Y1530024D02*
X885544Y1530615D01*
G01X888308Y1531133D02*
X888225Y1531215D01*
G01X887848Y1532077D02*
X888141Y1531830D01*
G01X887806D02*
X887513Y1532077D01*
G01X888434Y1531338D02*
X888560Y1531174D01*
G01X888350Y1531010D02*
X888308Y1531133D01*
G01X888560Y1531174D02*
X888602Y1530969D01*
G01X899892Y1524878D02*
Y1524386D01*
G01X899222Y1524550D02*
Y1525206D01*
G01X889481Y1532323D02*
Y1532077D01*
G01Y1530231D02*
Y1529985D01*
G01X888602Y1530969D02*
Y1530231D01*
G01X888350D02*
Y1531010D01*
G01X887722D02*
Y1530231D01*
G01X887513Y1532077D02*
Y1532323D01*
G01Y1529985D02*
Y1530969D01*
G01X886135Y1532544D02*
Y1530024D01*
G01X885544Y1530615D02*
Y1531954D01*
G01X884206Y1530615D02*
Y1531954D01*
G01X883615Y1532544D02*
Y1530024D01*
G01X882631Y1532544D02*
Y1530024D01*
G01X868969Y1536284D02*
Y1657957D01*
G01Y1536284D02*
Y1657957D01*
G01X887513Y1530969D02*
X887555Y1531174D01*
G01X899222Y1525206D02*
X899389Y1525698D01*
G01X887764Y1531133D02*
X887722Y1531010D01*
G01X900060Y1525206D02*
X899892Y1524878D01*
G01X887555Y1531174D02*
X887680Y1531338D01*
G01D02*
X887848Y1531461D01*
G01X900227Y1525370D02*
X900060Y1525206D01*
G01X899389Y1525698D02*
X899725Y1526026D01*
G01X887848Y1531215D02*
X887764Y1531133D01*
G01X885544Y1531954D02*
X886135Y1532544D01*
G01X884206Y1530615D02*
X883615Y1530024D01*
G01X887973Y1531256D02*
X887848Y1531215D01*
G01Y1531461D02*
X887973Y1531502D01*
G01X899725Y1526026D02*
X900562Y1526354D01*
G01Y1525534D02*
X900227Y1525370D01*
G01X922119Y1578213D02*
X868969D01*
G01X886848Y1673076D02*
G03X886258Y1672485I1J-591D01*
G01X886489Y1655635D02*
G03X887080Y1655044I591J0D01*
G01X886489Y1660753D02*
G03X885898Y1661343I-590J0D01*
G01X880387Y1666776D02*
G03X880190Y1666580I0J-197D01*
G01Y1665241D02*
G03X880387Y1665044I197J0D01*
G01Y1663076D02*
G03X880190Y1662879I0J-197D01*
G01Y1661540D02*
G03X880387Y1661343I197J0D01*
G01X866017Y1670162D02*
G03Y1657957I0J-6102D01*
G01X874875Y1677249D02*
X901646D01*
G01X897709Y1675635D02*
X899284D01*
G01X901646D02*
X899284D01*
G01X874875Y1675241D02*
X899284D01*
G01Y1675044D02*
X901253D01*
G01X899284D02*
X883103D01*
G01X901646D02*
X901253D01*
G01D02*
X899284D01*
G01Y1674493D02*
X878812D01*
G01X899284Y1673076D02*
X901253D01*
G01X886848D02*
X899284D01*
G01X901646D02*
X901253D01*
G01D02*
X899284D01*
G01X901646Y1672485D02*
X899678D01*
G01X880190Y1672090D02*
X874875D01*
G01X876253Y1671540D02*
X880190D01*
G01X896528Y1671072D02*
X880190D01*
G01X875465Y1670950D02*
X876253D01*
G01X874875Y1670162D02*
X866017D01*
G01X875465D02*
X874875D01*
G01X886258Y1669139D02*
X885471D01*
G01X882158Y1666776D02*
X880387D01*
G01X901646Y1665635D02*
X899678D01*
G01X899284Y1665044D02*
X901253D01*
G01X880387D02*
X899284D01*
G01X901646D02*
X901253D01*
G01D02*
X899284D01*
G01Y1663076D02*
X880387D01*
G01X901253D02*
X899284D01*
G01X901646D02*
X901253D01*
G01D02*
X899284D01*
G01X901646Y1662485D02*
X899678D01*
G01X880387Y1661343D02*
X885898D01*
G01X874875Y1657957D02*
X880190D01*
G01X874875D02*
X866017D01*
G01X880190Y1657918D02*
X874875D01*
G01X896528Y1657892D02*
X880190D01*
G01X901646Y1655635D02*
X899678D01*
G01X899284Y1655044D02*
X901253D01*
G01X887080D02*
X899284D01*
G01X901646D02*
X901253D01*
G01D02*
X899284D01*
G01X901253Y1654454D02*
X901353D01*
G01X901018D02*
X901253D01*
G01Y1654207D02*
X901311D01*
G01X899678D02*
X901253D01*
G01X901646Y1653961D02*
X901253D01*
G01D02*
X899678D01*
G01X899284Y1653627D02*
X878812D01*
G01X899284Y1653076D02*
X883024D01*
G01X901253D02*
X899284D01*
G01X901646D02*
X901253D01*
G01D02*
X899284D01*
G01X874875Y1652879D02*
X899284D01*
G01X897709Y1652485D02*
X899284D01*
G01X901646D02*
X899284D01*
G01X874875Y1650871D02*
X901646D01*
G01X863064Y1646934D02*
X905583D01*
G01X901353Y1654454D02*
X901646Y1654207D01*
G01X901311D02*
X901253Y1654257D01*
G01D02*
X901018Y1654454D01*
G01X899284Y1656107D02*
X897709Y1657997D01*
G01X899284Y1656107D02*
X899678Y1655635D01*
G01X899284Y1666343D02*
X897709Y1669178D01*
G01X899284Y1666343D02*
X899678Y1665635D01*
G01X883024Y1653076D02*
X880190Y1659590D01*
G01X901646Y1675044D02*
Y1677249D01*
G01Y1665044D02*
Y1673076D01*
G01Y1655044D02*
Y1663076D01*
G01Y1650871D02*
Y1653076D01*
G01Y1654207D02*
Y1653961D01*
G01X901253Y1655044D02*
Y1653076D01*
G01Y1665044D02*
Y1663076D01*
G01Y1675044D02*
Y1673076D01*
G01X900505Y1655044D02*
Y1653076D01*
G01Y1665044D02*
Y1663076D01*
G01Y1675044D02*
Y1673076D01*
G01X899678Y1653961D02*
Y1654207D01*
G01X899284Y1672091D02*
Y1675635D01*
G01Y1661776D02*
Y1666343D01*
G01Y1663076D02*
Y1665044D01*
G01Y1652485D02*
Y1656107D01*
G01Y1655044D02*
Y1653076D01*
G01Y1675044D02*
Y1673076D01*
G01X897709Y1652485D02*
Y1675635D01*
G01X896528Y1671072D02*
Y1657892D01*
G01X886489Y1660753D02*
Y1655635D01*
G01X886258Y1672485D02*
Y1669139D01*
G01X880387Y1661343D02*
Y1659137D01*
G01Y1665044D02*
Y1663076D01*
G01X880190Y1672090D02*
Y1657892D01*
G01Y1671540D02*
Y1657957D01*
G01X878812Y1674493D02*
Y1653627D01*
G01X876253Y1671540D02*
Y1657957D01*
G01X875465Y1670950D02*
Y1657957D01*
G01X874875Y1650871D02*
Y1677249D01*
G01X868969Y1670162D02*
Y1785654D01*
G01Y1670162D02*
Y1785654D01*
G01Y1657957D02*
Y1670162D01*
G01Y1657957D02*
Y1670162D01*
G01X866017Y1657957D02*
Y1670162D01*
G01X863064Y1658729D02*
Y1646934D01*
G01Y1669391D02*
Y1658729D01*
G01Y1681186D02*
Y1669391D01*
G01X897709Y1658942D02*
X899284Y1661776D01*
G01X899678Y1662485D02*
X899284Y1661776D01*
G01X880190Y1668351D02*
X883103Y1675044D01*
G01X897709Y1670517D02*
X899284Y1672091D01*
G01X899678Y1672485D02*
X899284Y1672091D01*
G01X885471Y1669139D02*
X882158Y1666776D01*
G01X863064Y1681186D02*
X905583D01*
G01X874875Y1778568D02*
X901646D01*
G01X863064Y1774631D02*
X905583D01*
G01X901646Y1778568D02*
Y1780772D01*
G01X874875Y1778568D02*
Y1804946D01*
G01X863064Y1786426D02*
Y1774631D01*
G01X886848Y1800772D02*
G03X886258Y1800182I0J-590D01*
G01X886489Y1783331D02*
G03X887080Y1782741I591J1D01*
G01X886489Y1788450D02*
G03X885898Y1789040I-591J-1D01*
G01X880387Y1794473D02*
G03X880190Y1794276I0J-197D01*
G01Y1792938D02*
G03X880387Y1792741I197J0D01*
G01Y1790772D02*
G03X880190Y1790576I0J-197D01*
G01Y1789237D02*
G03X880387Y1789040I197J0D01*
G01X866017Y1797859D02*
G03Y1785654I0J-6103D01*
G01X863064Y1808883D02*
X905583D01*
G01X874875Y1804946D02*
X901646D01*
G01X897709Y1803331D02*
X899284D01*
G01X901646D02*
X899284D01*
G01X874875Y1802938D02*
X899284D01*
G01Y1802741D02*
X901253D01*
G01X899284D02*
X883103D01*
G01X901646D02*
X901253D01*
G01D02*
X899284D01*
G01Y1802190D02*
X878812D01*
G01X899284Y1800772D02*
X901253D01*
G01X886848D02*
X899284D01*
G01X901646D02*
X901253D01*
G01D02*
X899284D01*
G01X901646Y1800182D02*
X899678D01*
G01X880190Y1799787D02*
X874875D01*
G01X876253Y1799237D02*
X880190D01*
G01X896528Y1798769D02*
X880190D01*
G01X875465Y1798646D02*
X876253D01*
G01X874875Y1797859D02*
X866017D01*
G01X875465D02*
X874875D01*
G01X886258Y1796835D02*
X885471D01*
G01X882158Y1794473D02*
X880387D01*
G01X901646Y1793331D02*
X899678D01*
G01X899284Y1792741D02*
X901253D01*
G01X880387D02*
X899284D01*
G01X901646D02*
X901253D01*
G01D02*
X899284D01*
G01Y1790772D02*
X880387D01*
G01X901253D02*
X899284D01*
G01X901646D02*
X901253D01*
G01D02*
X899284D01*
G01X901646Y1790182D02*
X899678D01*
G01X880387Y1789040D02*
X885898D01*
G01X874875Y1785654D02*
X880190D01*
G01X874875D02*
X866017D01*
G01X880190Y1785615D02*
X874875D01*
G01X896528Y1785588D02*
X880190D01*
G01X901646Y1783331D02*
X899678D01*
G01X899284Y1782741D02*
X901253D01*
G01X887080D02*
X899284D01*
G01X901646D02*
X901253D01*
G01D02*
X899284D01*
G01X901253Y1782150D02*
X901353D01*
G01X901018D02*
X901253D01*
G01Y1781904D02*
X901311D01*
G01X899678D02*
X901253D01*
G01X901646Y1781658D02*
X901253D01*
G01D02*
X899678D01*
G01X899284Y1781324D02*
X878812D01*
G01X899284Y1780772D02*
X883024D01*
G01X901253D02*
X899284D01*
G01X901646D02*
X901253D01*
G01D02*
X899284D01*
G01X874875Y1780576D02*
X899284D01*
G01X897709Y1780182D02*
X899284D01*
G01X901646D02*
X899284D01*
G01X901353Y1782150D02*
X901646Y1781904D01*
G01X901311D02*
X901253Y1781954D01*
G01D02*
X901018Y1782150D01*
G01X899284Y1783804D02*
X897709Y1785694D01*
G01X899284Y1783804D02*
X899678Y1783331D01*
G01X899284Y1794040D02*
X897709Y1796875D01*
G01X899284Y1794040D02*
X899678Y1793331D01*
G01X883024Y1780772D02*
X880190Y1787286D01*
G01X901646Y1802741D02*
Y1804946D01*
G01Y1792741D02*
Y1800772D01*
G01Y1782741D02*
Y1790772D01*
G01Y1781904D02*
Y1781658D01*
G01X901253Y1782741D02*
Y1780772D01*
G01Y1792741D02*
Y1790772D01*
G01Y1802741D02*
Y1800772D01*
G01X900505Y1782741D02*
Y1780772D01*
G01Y1792741D02*
Y1790772D01*
G01Y1802741D02*
Y1800772D01*
G01X899678Y1781658D02*
Y1781904D01*
G01X899284Y1799788D02*
Y1803331D01*
G01Y1789473D02*
Y1794040D01*
G01Y1790772D02*
Y1792741D01*
G01Y1780182D02*
Y1783804D01*
G01Y1782741D02*
Y1780772D01*
G01Y1802741D02*
Y1800772D01*
G01X897709Y1780182D02*
Y1803331D01*
G01X896528Y1798769D02*
Y1785588D01*
G01X886489Y1788450D02*
Y1783331D01*
G01X886258Y1800182D02*
Y1796835D01*
G01X880387Y1789040D02*
Y1786834D01*
G01Y1792741D02*
Y1790772D01*
G01X880190Y1799237D02*
Y1785654D01*
G01Y1799787D02*
Y1785588D01*
G01X878812Y1802190D02*
Y1781324D01*
G01X876253Y1799237D02*
Y1785654D01*
G01X875465Y1798646D02*
Y1785654D01*
G01X868969Y1797859D02*
Y1919513D01*
G01Y1797859D02*
Y1919513D01*
G01Y1785654D02*
Y1797859D01*
G01Y1785654D02*
Y1797859D01*
G01X866017Y1785654D02*
Y1797859D01*
G01X863064Y1797087D02*
Y1786426D01*
G01Y1808883D02*
Y1797087D01*
G01X880190Y1796048D02*
X883103Y1802741D01*
G01X897709Y1786639D02*
X899284Y1789473D01*
G01X899678Y1790182D02*
X899284Y1789473D01*
G01X897709Y1798213D02*
X899284Y1799788D01*
G01X899678Y1800182D02*
X899284Y1799788D01*
G01X885471Y1796835D02*
X882158Y1794473D01*
G01X903418Y1855143D02*
G03I-6890J0D01*
G01X912276D02*
G03I-15748J0D01*
G01X868969Y1877583D02*
X922119D01*
G01X882877Y1923253D02*
G03Y1925772I1998J1260D01*
G01Y1933253D02*
G03Y1935772I1998J1260D01*
G01Y1925772D02*
G03Y1923253I1998J-1260D01*
G01Y1935772D02*
G03Y1933253I1998J-1260D01*
G01X905977Y1901206D02*
G03I-7086J-1D01*
G01X893822Y1933439D02*
X901696D01*
G01X878969Y1933253D02*
X877788D01*
G01X886135D02*
X878969D01*
G01X897005Y1932454D02*
X893822D01*
G01X901696D02*
X898010D01*
G01X868969Y1931087D02*
X878969D01*
G01X868969Y1930300D02*
X878969D01*
G01Y1928725D02*
X868969D01*
G01X878969Y1927938D02*
X868969D01*
G01X898010Y1927861D02*
X901696D01*
G01X893822D02*
X897005D01*
G01X901696Y1926877D02*
X893822D01*
G01X878969Y1925772D02*
X877788D01*
G01X886135D02*
X878969D01*
G01X885544Y1925182D02*
X884206D01*
G01Y1923843D02*
X885544D01*
G01X878969Y1923253D02*
X877788D01*
G01X886135D02*
X878969D01*
G01X868969Y1921087D02*
X878969D01*
G01X868969Y1920300D02*
X878969D01*
G01X868969Y1919513D02*
X878969D01*
G01X886135Y1933253D02*
X885544Y1933843D01*
G01X886135Y1923253D02*
X885544Y1923843D01*
G01X884206Y1925182D02*
X883615Y1925772D01*
G01X901696Y1927861D02*
Y1926877D01*
G01Y1933439D02*
Y1932454D01*
G01X898010D02*
Y1927861D01*
G01X897005D02*
Y1932454D01*
G01X893822D02*
Y1933439D01*
G01Y1926877D02*
Y1927861D01*
G01X886135Y1925772D02*
Y1923253D01*
G01Y1935772D02*
Y1933253D01*
G01X885544Y1923843D02*
Y1925182D01*
G01X884206Y1923843D02*
Y1925182D01*
G01X883615Y1925772D02*
Y1923253D01*
G01Y1935772D02*
Y1933253D01*
G01X882631Y1925772D02*
Y1923253D01*
G01Y1935772D02*
Y1933253D01*
G01X878969Y1919513D02*
Y1969513D01*
G01X877788D02*
Y1919513D01*
G01X868969D02*
Y1969513D01*
G01Y1919513D02*
Y1969513D01*
G01Y1919513D02*
Y1969513D01*
G01X885544Y1925182D02*
X886135Y1925772D01*
G01X884206Y1923843D02*
X883615Y1923253D01*
G01X884206Y1933843D02*
X883615Y1933253D01*
G01X882877Y1943253D02*
G03Y1945772I1998J1260D01*
G01Y1953253D02*
G03Y1955772I1998J1260D01*
G01Y1963253D02*
G03Y1965772I1998J1260D01*
G01Y1945772D02*
G03Y1943253I1998J-1260D01*
G01Y1955772D02*
G03Y1953253I1998J-1260D01*
G01Y1965772D02*
G03Y1963253I1998J-1260D01*
G01X905977Y1987820D02*
G03I-7086J0D01*
G01X899350Y1944430D02*
X898513Y1944594D01*
G01X896167Y1938852D02*
X897005Y1938688D01*
G01X899350Y1943609D02*
X898345Y1943773D01*
G01X896167Y1939672D02*
X897172Y1939508D01*
G01X868969Y1969513D02*
X878969D01*
G01Y1968725D02*
X868969D01*
G01X878969Y1967938D02*
X868969D01*
G01X878969Y1965772D02*
X877788D01*
G01X886135D02*
X878969D01*
G01X887513Y1965551D02*
X889481D01*
G01Y1965305D02*
X887848D01*
G01X885544Y1965182D02*
X884206D01*
G01X888141Y1965059D02*
X887806D01*
G01X887973Y1964731D02*
X888141D01*
G01X888099Y1964485D02*
X887973D01*
G01X884206Y1963843D02*
X885544D01*
G01X887722Y1963459D02*
X888350D01*
G01X888602D02*
X889481D01*
G01X878969Y1963253D02*
X877788D01*
G01X886135D02*
X878969D01*
G01X889481Y1963213D02*
X887513D01*
G01X868969Y1961087D02*
X878969D01*
G01X868969Y1960300D02*
X878969D01*
G01X897675Y1959357D02*
X901696D01*
G01X878969Y1958725D02*
X868969D01*
G01X901696Y1958537D02*
X897675D01*
G01X878969Y1957938D02*
X868969D01*
G01X897675Y1956733D02*
X901696D01*
G01Y1955912D02*
X897675D01*
G01X878969Y1955772D02*
X877788D01*
G01X886135D02*
X878969D01*
G01X885544Y1955182D02*
X884206D01*
G01X897507Y1954108D02*
X901696D01*
G01X896335D02*
X896837D01*
G01X884206Y1953843D02*
X885544D01*
G01X901696Y1953288D02*
X896335D01*
G01X878969Y1953253D02*
X877788D01*
G01X886135D02*
X878969D01*
G01X897675Y1951975D02*
X901696D01*
G01Y1951155D02*
X897675D01*
G01X868969Y1951087D02*
X878969D01*
G01X868969Y1950300D02*
X878969D01*
G01X897675Y1949351D02*
X901696D01*
G01X878969Y1948725D02*
X868969D01*
G01X901696Y1948531D02*
X897675D01*
G01X878969Y1947938D02*
X868969D01*
G01X897507Y1946726D02*
X901696D01*
G01X896335D02*
X896837D01*
G01X901696Y1945906D02*
X896335D01*
G01X878969Y1945772D02*
X877788D01*
G01X886135D02*
X878969D01*
G01X885544Y1945182D02*
X884206D01*
G01X898513Y1944594D02*
X897005D01*
G01X884206Y1943843D02*
X885544D01*
G01X898345Y1943773D02*
X897172D01*
G01X878969Y1943253D02*
X877788D01*
G01X886135D02*
X878969D01*
G01X868969Y1941087D02*
X878969D01*
G01X868969Y1940300D02*
X878969D01*
G01X897172Y1939508D02*
X898345D01*
G01X878969Y1938725D02*
X868969D01*
G01X897005Y1938688D02*
X898513D01*
G01X878969Y1937938D02*
X868969D01*
G01X898345Y1937376D02*
X899015D01*
G01X896335D02*
X897005D01*
G01X878969Y1935772D02*
X877788D01*
G01X886135D02*
X878969D01*
G01X885544Y1935182D02*
X884206D01*
G01X899015Y1934751D02*
X898345D01*
G01X897005D02*
X896335D01*
G01X884206Y1933843D02*
X885544D01*
G01X897172Y1943773D02*
X896167Y1943609D01*
G01X898345Y1939508D02*
X899350Y1939672D01*
G01X897005Y1944594D02*
X896167Y1944430D01*
G01X898513Y1938688D02*
X899350Y1938852D01*
G01X897340Y1956897D02*
X897675Y1956733D01*
G01X888141Y1964731D02*
X888267Y1964690D01*
G01X888225Y1964444D02*
X888099Y1964485D01*
G01X899853Y1944266D02*
X899350Y1944430D01*
G01X895665Y1939016D02*
X896167Y1938852D01*
G01X897340Y1949515D02*
X897675Y1949351D01*
G01X900523Y1943937D02*
X899853Y1944266D01*
G01X894994Y1939344D02*
X895665Y1939016D01*
G01X887848Y1965305D02*
X888141Y1965059D01*
G01X887806D02*
X887513Y1965305D01*
G01X888267Y1964690D02*
X888434Y1964567D01*
G01X900356Y1942953D02*
X899350Y1943609D01*
G01X895162Y1940328D02*
X896167Y1939672D01*
G01X884206Y1965182D02*
X883615Y1965772D01*
G01X886135Y1963253D02*
X885544Y1963843D01*
G01X897172Y1957061D02*
X897340Y1956897D01*
G01X897005Y1956569D02*
X896502Y1957061D01*
G01X888308Y1964362D02*
X888225Y1964444D01*
G01X897172Y1954436D02*
X897507Y1954108D01*
G01X896837D02*
X896502Y1954436D01*
G01X897172Y1949679D02*
X897340Y1949515D01*
G01X897005Y1949187D02*
X896502Y1949679D01*
G01X901026Y1943445D02*
X900523Y1943937D01*
G01X897172Y1947054D02*
X897507Y1946726D01*
G01X896837D02*
X896502Y1947054D01*
G01X894492Y1939836D02*
X894994Y1939344D01*
G01X884206Y1955182D02*
X883615Y1955772D01*
G01X886135Y1953253D02*
X885544Y1953843D01*
G01X884206Y1945182D02*
X883615Y1945772D01*
G01X886135Y1943253D02*
X885544Y1943843D01*
G01X884206Y1935182D02*
X883615Y1935772D01*
G01X888434Y1964567D02*
X888560Y1964403D01*
G01X901528Y1942625D02*
X901026Y1943445D01*
G01X893989Y1940657D02*
X894492Y1939836D01*
G01X900691Y1942461D02*
X900356Y1942953D01*
G01X894827Y1940821D02*
X895162Y1940328D01*
G01X897005Y1957389D02*
X897172Y1957061D01*
G01X897005Y1950007D02*
X897172Y1949679D01*
G01X896502Y1957061D02*
X896335Y1957553D01*
G01X897005Y1954928D02*
X897172Y1954436D01*
G01X896502D02*
X896335Y1954928D01*
G01X896502Y1949679D02*
X896335Y1950171D01*
G01X897005Y1947546D02*
X897172Y1947054D01*
G01X896502D02*
X896335Y1947546D01*
G01X888350Y1964239D02*
X888308Y1964362D01*
G01X901696Y1941641D02*
X901528Y1942625D01*
G01X893822Y1941641D02*
X893989Y1940657D01*
G01X900858Y1941641D02*
X900691Y1942461D01*
G01X894659Y1941641D02*
X894827Y1940821D01*
G01X888560Y1964403D02*
X888602Y1964198D01*
G01X901696Y1949351D02*
Y1948531D01*
G01Y1946726D02*
Y1945906D01*
G01Y1951975D02*
Y1951155D01*
G01Y1954108D02*
Y1953288D01*
G01Y1956733D02*
Y1955912D01*
G01Y1959357D02*
Y1958537D01*
G01X899015Y1937376D02*
Y1934751D01*
G01X898345D02*
Y1937376D01*
G01X897005D02*
Y1934751D01*
G01Y1947874D02*
Y1947546D01*
G01Y1950499D02*
Y1950007D01*
G01Y1955256D02*
Y1954928D01*
G01Y1957881D02*
Y1957389D01*
G01X896335Y1957553D02*
Y1958209D01*
G01Y1954928D02*
Y1955584D01*
G01Y1953288D02*
Y1954108D01*
G01Y1950171D02*
Y1950827D01*
G01Y1947546D02*
Y1948203D01*
G01Y1945906D02*
Y1946726D01*
G01Y1934751D02*
Y1937376D01*
G01X889481Y1965551D02*
Y1965305D01*
G01Y1963459D02*
Y1963213D01*
G01X888602Y1964198D02*
Y1963459D01*
G01X888350D02*
Y1964239D01*
G01X887722D02*
Y1963459D01*
G01X887513Y1965305D02*
Y1965551D01*
G01Y1963213D02*
Y1964198D01*
G01X886135Y1945772D02*
Y1943253D01*
G01Y1955772D02*
Y1953253D01*
G01Y1965772D02*
Y1963253D01*
G01X885544Y1963843D02*
Y1965182D01*
G01Y1953843D02*
Y1955182D01*
G01Y1943843D02*
Y1945182D01*
G01Y1933843D02*
Y1935182D01*
G01X884206Y1963843D02*
Y1965182D01*
G01Y1953843D02*
Y1955182D01*
G01Y1943843D02*
Y1945182D01*
G01Y1933843D02*
Y1935182D01*
G01X883615Y1945772D02*
Y1943253D01*
G01Y1955772D02*
Y1953253D01*
G01Y1965772D02*
Y1963253D01*
G01X882631Y1945772D02*
Y1943253D01*
G01Y1955772D02*
Y1953253D01*
G01Y1965772D02*
Y1963253D01*
G01X868969Y1969513D02*
Y2008686D01*
G01Y1969513D02*
Y2008686D01*
G01X900691Y1940821D02*
X900858Y1941641D01*
G01X894827Y1942461D02*
X894659Y1941641D01*
G01X901528Y1940657D02*
X901696Y1941641D01*
G01X893989Y1942625D02*
X893822Y1941641D01*
G01X887513Y1964198D02*
X887555Y1964403D01*
G01X896335Y1948203D02*
X896502Y1948695D01*
G01X896335Y1950827D02*
X896502Y1951319D01*
G01X896335Y1955584D02*
X896502Y1956077D01*
G01X896335Y1958209D02*
X896502Y1958701D01*
G01X887764Y1964362D02*
X887722Y1964239D01*
G01X897172Y1948203D02*
X897005Y1947874D01*
G01X897172Y1950827D02*
X897005Y1950499D01*
G01X897172Y1955584D02*
X897005Y1955256D01*
G01X897172Y1958209D02*
X897005Y1957881D01*
G01X900356Y1940328D02*
X900691Y1940821D01*
G01X895162Y1942953D02*
X894827Y1942461D01*
G01X901026Y1939836D02*
X901528Y1940657D01*
G01X894492Y1943445D02*
X893989Y1942625D01*
G01X887555Y1964403D02*
X887680Y1964567D01*
G01X900523Y1939344D02*
X901026Y1939836D01*
G01X894994Y1943937D02*
X894492Y1943445D01*
G01X897340Y1948367D02*
X897172Y1948203D01*
G01X896502Y1948695D02*
X897005Y1949187D01*
G01X897340Y1950991D02*
X897172Y1950827D01*
G01X896502Y1951319D02*
X896837Y1951647D01*
G01X897340Y1955748D02*
X897172Y1955584D01*
G01X896502Y1956077D02*
X897005Y1956569D01*
G01X897340Y1958373D02*
X897172Y1958209D01*
G01X896502Y1958701D02*
X896837Y1959029D01*
G01X885544Y1935182D02*
X886135Y1935772D01*
G01X885544Y1945182D02*
X886135Y1945772D01*
G01X884206Y1943843D02*
X883615Y1943253D01*
G01X885544Y1955182D02*
X886135Y1955772D01*
G01X884206Y1953843D02*
X883615Y1953253D01*
G01X885544Y1965182D02*
X886135Y1965772D01*
G01X884206Y1963843D02*
X883615Y1963253D01*
G01X887848Y1964444D02*
X887764Y1964362D01*
G01X899853Y1939016D02*
X900523Y1939344D01*
G01X899350Y1939672D02*
X900356Y1940328D01*
G01X896167Y1943609D02*
X895162Y1942953D01*
G01X887680Y1964567D02*
X887848Y1964690D01*
G01X899350Y1938852D02*
X899853Y1939016D01*
G01X896167Y1944430D02*
X895665Y1944266D01*
G01X887973Y1964485D02*
X887848Y1964444D01*
G01Y1964690D02*
X887973Y1964731D01*
G01X896837Y1951647D02*
X897675Y1951975D01*
G01X896837Y1959029D02*
X897675Y1959357D01*
G01X895665Y1944266D02*
X894994Y1943937D01*
G01X897675Y1948531D02*
X897340Y1948367D01*
G01X897675Y1951155D02*
X897340Y1950991D01*
G01X897675Y1955912D02*
X897340Y1955748D01*
G01X897675Y1958537D02*
X897340Y1958373D01*
G01X872906Y2012623D02*
G03X868969Y2008686I0J-3937D01*
G01X872906Y2012623D02*
G03X868969Y2008686I0J-3937D01*
G01X872906Y2012623D02*
X933930D01*
G01X872906D02*
X933930D01*
G01X922119Y2011442D02*
X870095D01*
G01X900465Y2097521D02*
X900749Y2099983D01*
X901175Y2102066D01*
X901743Y2103959D01*
X902453Y2106042D01*
X903590Y2108883D01*
X897908D01*
G01X941804Y83489D02*
G03X937867Y79552I0J-3937D01*
G01X941804Y83489D02*
G03X937867Y79552I0J-3937D01*
G01X933930Y44119D02*
G03X937867Y48056I0J3937D01*
G01X933930Y44119D02*
G03X937867Y48056I0J3937D01*
G01X922119Y45300D02*
G03X931961Y55143I0J9842D01*
G01X937867Y79552D02*
Y48056D01*
G01Y79552D02*
Y48056D01*
G01X931961Y55143D02*
Y169316D01*
G01X1071725Y83489D02*
X941804D01*
G01X1071725D02*
X941804D01*
G01X921922Y112229D02*
G03I-5709J0D01*
G01X954580Y183528D02*
G03I-4902J0D01*
G01X955778Y163528D02*
G03I-6100J0D01*
G01X955938D02*
G03I-6260J0D01*
G01X931961Y169316D02*
G03X922119Y179158I-9842J0D01*
G01X951028Y188478D02*
Y178578D01*
G01X948328D02*
Y188478D01*
G01X938978Y187528D02*
Y349528D01*
G01X935978Y153528D02*
Y383528D01*
G01X934678Y152032D02*
Y385024D01*
G01X948328Y188478D02*
X951028D01*
G01X955478Y187528D02*
X938978D01*
G01X935978Y183528D02*
X963378D01*
G01X951028Y178578D02*
X948328D01*
G01X935978Y153528D02*
X963378D01*
G01X994678Y152032D02*
X934678D01*
G01X951408Y207028D02*
G03X947948I-1730J-1019D01*
G01X951408Y227028D02*
G03X947948I-1730J-1019D01*
G01X947926Y215028D02*
G03X951430I1752J981D01*
G01X947926Y235028D02*
G03X951430I1752J981D01*
G01X947948Y207028D02*
G03X951408I1730J-1019D01*
G01X947948Y227028D02*
G03X951408I1730J-1019D01*
G01X951430Y215028D02*
G03X947926I-1752J981D01*
G01X951430Y235028D02*
G03X947926I-1752J981D01*
G01X952315Y207028D02*
Y205028D01*
G01Y217028D02*
Y215028D01*
G01Y227028D02*
Y225028D01*
G01Y237028D02*
Y235028D01*
G01X950928D02*
Y237028D01*
G01Y225028D02*
Y227028D01*
G01Y215028D02*
Y217028D01*
G01Y205028D02*
Y207028D01*
G01X948428D02*
Y205028D01*
G01Y217028D02*
Y215028D01*
G01Y227028D02*
Y225028D01*
G01Y237028D02*
Y235028D01*
G01X947522D02*
Y237028D01*
G01Y225028D02*
Y227028D01*
G01Y215028D02*
Y217028D01*
G01Y205028D02*
Y207028D01*
G01X946908Y227028D02*
Y235028D01*
G01Y207028D02*
Y215028D01*
G01X941178Y243528D02*
Y293528D01*
G01X940978Y198528D02*
Y243528D01*
G01X938982D02*
X941178D01*
G01X947522Y237028D02*
X978384D01*
G01X946908Y235028D02*
X982308D01*
G01X946908Y227028D02*
X982308D01*
G01X947522Y225028D02*
X978384D01*
G01X947522Y217028D02*
X978384D01*
G01X946908Y215028D02*
X982308D01*
G01X946908Y207028D02*
X982308D01*
G01X947522Y205028D02*
X978384D01*
G01X938978Y198528D02*
X990378D01*
G01X951686Y268528D02*
G03I-2008J0D01*
G01Y278528D02*
G03I-2008J0D01*
G01Y288528D02*
G03I-2008J0D01*
G01Y248528D02*
G03I-2008J0D01*
G01Y258528D02*
G03I-2008J0D01*
G01X948037Y246888D02*
X948428Y247278D01*
G01X951318Y250169D02*
X950928Y249778D01*
G01X948037Y256888D02*
X948428Y257278D01*
G01X951318Y260169D02*
X950928Y259778D01*
G01X948037Y266888D02*
X948428Y267278D01*
G01X951318Y270169D02*
X950928Y269778D01*
G01X948037Y276888D02*
X948428Y277278D01*
G01X951318Y280169D02*
X950928Y279778D01*
G01X948037Y286888D02*
X948428Y287278D01*
G01X951318Y290169D02*
X950928Y289778D01*
G01X951318Y250169D02*
Y246888D01*
G01Y260169D02*
Y256888D01*
G01Y270169D02*
Y266888D01*
G01Y280169D02*
Y276888D01*
G01Y290169D02*
Y286888D01*
G01X951058Y249908D02*
Y247148D01*
G01Y259908D02*
Y257148D01*
G01Y269908D02*
Y267148D01*
G01Y279908D02*
Y277148D01*
G01Y289908D02*
Y287148D01*
G01X950928Y249778D02*
Y247278D01*
G01Y259778D02*
Y257278D01*
G01Y269778D02*
Y267278D01*
G01Y279778D02*
Y277278D01*
G01Y289778D02*
Y287278D01*
G01X948428D02*
Y289778D01*
G01Y277278D02*
Y279778D01*
G01Y267278D02*
Y269778D01*
G01Y257278D02*
Y259778D01*
G01Y247278D02*
Y249778D01*
G01X948298Y287148D02*
Y289908D01*
G01Y277148D02*
Y279908D01*
G01Y267148D02*
Y269908D01*
G01Y257148D02*
Y259908D01*
G01Y247148D02*
Y249908D01*
G01X948037Y286888D02*
Y290169D01*
G01Y276888D02*
Y280169D01*
G01Y266888D02*
Y270169D01*
G01Y256888D02*
Y260169D01*
G01Y246888D02*
Y250169D01*
G01X940978Y293528D02*
Y338528D01*
G01X905583Y247859D02*
Y282111D01*
G01X950928Y287278D02*
X951318Y286888D01*
G01X948037Y290169D02*
X948428Y289778D01*
G01X950928Y277278D02*
X951318Y276888D01*
G01X948037Y280169D02*
X948428Y279778D01*
G01X950928Y267278D02*
X951318Y266888D01*
G01X948037Y270169D02*
X948428Y269778D01*
G01X950928Y257278D02*
X951318Y256888D01*
G01X948037Y260169D02*
X948428Y259778D01*
G01X950928Y247278D02*
X951318Y246888D01*
G01X948037Y250169D02*
X948428Y249778D01*
G01X938982Y293528D02*
X941178D01*
G01X948037Y290169D02*
X951318D01*
G01X948298Y289908D02*
X951058D01*
G01X948428Y289778D02*
X950928D01*
G01Y287278D02*
X948428D01*
G01X951058Y287148D02*
X948298D01*
G01X951318Y286888D02*
X948037D01*
G01Y280169D02*
X951318D01*
G01X948298Y279908D02*
X951058D01*
G01X948428Y279778D02*
X950928D01*
G01Y277278D02*
X948428D01*
G01X951058Y277148D02*
X948298D01*
G01X951318Y276888D02*
X948037D01*
G01Y270169D02*
X951318D01*
G01X948298Y269908D02*
X951058D01*
G01X948428Y269778D02*
X950928D01*
G01Y267278D02*
X948428D01*
G01X951058Y267148D02*
X948298D01*
G01X951318Y266888D02*
X948037D01*
G01Y260169D02*
X951318D01*
G01X948298Y259908D02*
X951058D01*
G01X948428Y259778D02*
X950928D01*
G01Y257278D02*
X948428D01*
G01X951058Y257148D02*
X948298D01*
G01X951318Y256888D02*
X948037D01*
G01Y250169D02*
X951318D01*
G01X948298Y249908D02*
X951058D01*
G01X948428Y249778D02*
X950928D01*
G01Y247278D02*
X948428D01*
G01X951058Y247148D02*
X948298D01*
G01X951318Y246888D02*
X948037D01*
G01X951430Y322029D02*
G03X947926I-1752J-981D01*
G01X947948Y330028D02*
G03X951408I1730J1020D01*
G01X947926Y322029D02*
G03X951430I1752J-981D01*
G01X951408Y330028D02*
G03X947948I-1730J1020D01*
G01X951430Y302029D02*
G03X947926I-1752J-981D01*
G01X947948Y310028D02*
G03X951408I1730J1020D01*
G01X947926Y302029D02*
G03X951430I1752J-981D01*
G01X951408Y310028D02*
G03X947948I-1730J1020D01*
G01X952816Y330875D02*
X952740Y330850D01*
G01Y330998D02*
X952816Y331022D01*
G01X952916Y330949D02*
X952816Y330875D01*
G01Y331022D02*
X952866Y331072D01*
G01X952991Y331047D02*
X952916Y330949D01*
G01X952866Y331072D02*
X952891Y331145D01*
G01X953017Y331170D02*
X952991Y331047D01*
G01X953017Y330506D02*
Y330358D01*
G01Y331761D02*
Y331170D01*
G01X952891Y331145D02*
Y331613D01*
G01X952514D02*
Y331145D01*
G01X952363Y331170D02*
Y331613D01*
G01X952315Y302028D02*
Y300028D01*
G01Y312028D02*
Y310028D01*
G01Y322028D02*
Y320028D01*
G01Y332028D02*
Y330028D01*
G01X951835Y331613D02*
Y331761D01*
G01Y330358D02*
Y330506D01*
G01X950928Y330028D02*
Y332028D01*
G01Y320028D02*
Y322028D01*
G01Y310028D02*
Y312028D01*
G01Y300028D02*
Y302028D01*
G01X948428D02*
Y300028D01*
G01Y312028D02*
Y310028D01*
G01Y322028D02*
Y320028D01*
G01Y332028D02*
Y330028D01*
G01X947522D02*
Y332028D01*
G01Y320028D02*
Y322028D01*
G01Y310028D02*
Y312028D01*
G01Y300028D02*
Y302028D01*
G01X946908Y322028D02*
Y330028D01*
G01Y302028D02*
Y310028D01*
G01X952388Y331047D02*
X952363Y331170D01*
G01X952514Y331145D02*
X952539Y331072D01*
G01X952464Y330949D02*
X952388Y331047D01*
G01X952539Y331072D02*
X952589Y331022D01*
G01X952841Y330653D02*
X953017Y330506D01*
G01X952816D02*
X952640Y330653D01*
G01X952564Y330875D02*
X952464Y330949D01*
G01X952589Y331022D02*
X952665Y330998D01*
G01X952640Y330850D02*
X952564Y330875D01*
G01X938978Y338528D02*
X990378D01*
G01X947522Y332028D02*
X978384D01*
G01X951835Y331761D02*
X953017D01*
G01X952891Y331613D02*
X952514D01*
G01X952363D02*
X951835D01*
G01X952665Y330998D02*
X952740D01*
G01Y330850D02*
X952640D01*
G01Y330653D02*
X952841D01*
G01X951835Y330506D02*
X952816D01*
G01X953017Y330358D02*
X951835D01*
G01X946908Y330028D02*
X982308D01*
G01X946908Y322028D02*
X982308D01*
G01X947522Y320028D02*
X978384D01*
G01X947522Y312028D02*
X978384D01*
G01X946908Y310028D02*
X982308D01*
G01X946908Y302028D02*
X982308D01*
G01X947522Y300028D02*
X978384D01*
G01X954580Y353528D02*
G03I-4902J0D01*
G01X955778Y373528D02*
G03I-6100J0D01*
G01X955938D02*
G03I-6260J0D01*
G01X951028Y358478D02*
Y348578D01*
G01X948328D02*
Y358478D01*
G01X905583Y375556D02*
Y409808D01*
G01X934678Y385024D02*
X994678D01*
G01X963378Y383528D02*
X935978D01*
G01X948328Y358478D02*
X951028D01*
G01X963378Y353528D02*
X935978D01*
G01X938978Y349528D02*
X955478D01*
G01X951028Y348578D02*
X948328D01*
G01X922119Y478528D02*
G03X931961Y488371I0J9842D01*
G01D02*
Y602544D01*
G01X921922Y545457D02*
G03I-5709J0D01*
G01X904262Y538299D02*
X904764Y538463D01*
G01D02*
X905434Y538791D01*
G01X904262Y539119D02*
X905267Y539775D01*
G01X905434Y538791D02*
X905937Y539283D01*
G01X905267Y539775D02*
X905602Y540267D01*
G01X905937Y539283D02*
X906440Y540103D01*
G01X905602Y540267D02*
X905769Y541087D01*
G01X906440Y540103D02*
X906607Y541087D01*
G01Y527308D02*
Y526324D01*
G01Y532885D02*
Y531901D01*
G01Y548797D02*
Y547977D01*
G01Y546173D02*
Y545352D01*
G01Y551422D02*
Y550602D01*
G01X903927Y536822D02*
Y534198D01*
G01X906607Y541087D02*
X906440Y542072D01*
G01X905769Y541087D02*
X905602Y541908D01*
G01X906440Y542072D02*
X905937Y542892D01*
G01X905602Y541908D02*
X905267Y542400D01*
G01X905937Y542892D02*
X905434Y543384D01*
G01X905267Y542400D02*
X904262Y543056D01*
G01X905434Y543384D02*
X904764Y543712D01*
G01D02*
X904262Y543876D01*
G01X931961Y602544D02*
G03X922119Y612387I-9843J0D01*
G01X906607Y553555D02*
Y552734D01*
G01Y556179D02*
Y555359D01*
G01Y558804D02*
Y557984D01*
G01X922119Y738371D02*
G03X931961Y748213I0J9842D01*
G01D02*
Y862387D01*
G01X921922Y805300D02*
G03I-5709J0D01*
G01X903899Y799499D02*
X904402Y799992D01*
G01D02*
X904904Y800812D01*
G01X904066Y800976D02*
X904234Y801796D01*
G01X904904Y800812D02*
X905072Y801796D01*
G01Y788017D02*
Y787032D01*
G01Y793594D02*
Y792610D01*
G01Y806881D02*
Y806061D01*
G01Y801796D02*
X904904Y802780D01*
G01X904234Y801796D02*
X904066Y802616D01*
G01X904904Y802780D02*
X904402Y803601D01*
G01D02*
X903899Y804093D01*
G01X905072Y809506D02*
Y808686D01*
G01Y812131D02*
Y811310D01*
G01Y816888D02*
Y816068D01*
G01Y814263D02*
Y813443D01*
G01Y819513D02*
Y818692D01*
G01X931961Y862387D02*
G03X922119Y872229I-9842J0D01*
G01X905583Y940910D02*
Y975162D01*
G01Y1081580D02*
Y1115831D01*
G01X922119Y1184513D02*
G03X931961Y1194355I0J9842D01*
G01D02*
Y1308528D01*
G01X921922Y1251442D02*
G03I-5709J0D01*
G01X931961Y1308528D02*
G03X922119Y1318371I-9842J1D01*
G01X1021332Y1318922D02*
X904402D01*
G01Y1426796D02*
Y1318922D01*
G01X941280Y1365576D02*
X939940D01*
G01X945301D02*
X943961D01*
G01X934914Y1362951D02*
X950662D01*
G01X941280Y1360982D02*
X934914D01*
G01X950662D02*
X943291D01*
G01Y1351796D02*
X950662D01*
G01X934914D02*
X941280D01*
G01X950662Y1349828D02*
X934914D01*
G01X950662Y1351796D02*
Y1349828D01*
G01Y1362951D02*
Y1360982D01*
G01X945301Y1370825D02*
Y1365576D01*
G01X943961D02*
Y1370825D01*
G01X943291Y1360982D02*
Y1351796D01*
G01X941280D02*
Y1360982D01*
G01Y1370825D02*
Y1365576D01*
G01X939940D02*
Y1370825D01*
G01X934914Y1360982D02*
Y1362951D01*
G01Y1349828D02*
Y1351796D01*
G01X945971Y1384933D02*
X944296Y1385261D01*
G01X945971Y1383292D02*
X943961Y1383620D01*
G01X942621Y1414788D02*
X950662D01*
G01Y1413148D02*
X942621D01*
G01Y1409539D02*
X950662D01*
G01Y1407898D02*
X942621D01*
G01X942286Y1404289D02*
X950662D01*
G01X939940D02*
X940945D01*
G01X950662Y1402649D02*
X939940D01*
G01X942621Y1400024D02*
X950662D01*
G01Y1398384D02*
X942621D01*
G01Y1394775D02*
X950662D01*
G01Y1393135D02*
X942621D01*
G01X942286Y1389526D02*
X950662D01*
G01X939940D02*
X940945D01*
G01X950662Y1387885D02*
X939940D01*
G01X944296Y1385261D02*
X941280D01*
G01X943961Y1383620D02*
X941615D01*
G01Y1375090D02*
X943961D01*
G01X941280Y1373450D02*
X944296D01*
G01X943961Y1370825D02*
X945301D01*
G01X939940D02*
X941280D01*
G01X941615Y1383620D02*
X939605Y1383292D01*
G01X943961Y1375090D02*
X945971Y1375418D01*
G01X941280Y1385261D02*
X939605Y1384933D01*
G01X944296Y1373450D02*
X945971Y1373778D01*
G01X947982Y1381980D02*
X945971Y1383292D01*
G01X937595Y1376730D02*
X939605Y1375418D01*
G01X941951Y1409867D02*
X942621Y1409539D01*
G01X941951Y1395103D02*
X942621Y1394775D01*
G01X948317Y1383948D02*
X946977Y1384604D01*
G01X937260Y1374762D02*
X938600Y1374106D01*
G01X946977Y1384604D02*
X945971Y1384933D01*
G01X938600Y1374106D02*
X939605Y1373778D01*
G01D02*
X941280Y1373450D01*
G01X939605Y1375418D02*
X941615Y1375090D01*
G01Y1410195D02*
X941951Y1409867D01*
G01X941280Y1409211D02*
X940275Y1410195D01*
G01X941615Y1404946D02*
X942286Y1404289D01*
G01X940945D02*
X940275Y1404946D01*
G01X941615Y1395431D02*
X941951Y1395103D01*
G01X941280Y1394447D02*
X940275Y1395431D01*
G01X949322Y1382964D02*
X948317Y1383948D01*
G01X941615Y1390182D02*
X942286Y1389526D01*
G01X940945D02*
X940275Y1390182D01*
G01X936254Y1375746D02*
X937260Y1374762D01*
G01X941280Y1410851D02*
X941615Y1410195D01*
G01X941280Y1396087D02*
X941615Y1395431D01*
G01X950327Y1381324D02*
X949322Y1382964D01*
G01X935249Y1377387D02*
X936254Y1375746D01*
G01X948652Y1380996D02*
X947982Y1381980D01*
G01X936925Y1377715D02*
X937595Y1376730D01*
G01X940275Y1410195D02*
X939940Y1411179D01*
G01X941280Y1405930D02*
X941615Y1404946D01*
G01X940275D02*
X939940Y1405930D01*
G01X940275Y1395431D02*
X939940Y1396415D01*
G01X941280Y1391166D02*
X941615Y1390182D01*
G01X940275D02*
X939940Y1391166D01*
G01X950662Y1379355D02*
X950327Y1381324D01*
G01X934914Y1379355D02*
X935249Y1377387D01*
G01X948987Y1379355D02*
X948652Y1380996D01*
G01X936590Y1379355D02*
X936925Y1377715D01*
G01X950662Y1389526D02*
Y1387885D01*
G01Y1394775D02*
Y1393135D01*
G01Y1400024D02*
Y1398384D01*
G01Y1404289D02*
Y1402649D01*
G01Y1409539D02*
Y1407898D01*
G01Y1414788D02*
Y1413148D01*
G01X941280Y1391822D02*
Y1391166D01*
G01Y1397072D02*
Y1396087D01*
G01Y1406586D02*
Y1405930D01*
G01Y1411835D02*
Y1410851D01*
G01X939940Y1411179D02*
Y1412492D01*
G01Y1405930D02*
Y1407242D01*
G01Y1402649D02*
Y1404289D01*
G01Y1396415D02*
Y1397728D01*
G01Y1391166D02*
Y1392478D01*
G01Y1387885D02*
Y1389526D01*
G01X948652Y1377715D02*
X948987Y1379355D01*
G01X936925Y1380996D02*
X936590Y1379355D01*
G01X950327Y1377387D02*
X950662Y1379355D01*
G01X935249Y1381324D02*
X934914Y1379355D01*
G01X941615Y1392478D02*
X941280Y1391822D01*
G01X941615Y1397728D02*
X941280Y1397072D01*
G01X941615Y1407242D02*
X941280Y1406586D01*
G01X939940Y1392478D02*
X940275Y1393463D01*
G01X939940Y1397728D02*
X940275Y1398712D01*
G01X939940Y1407242D02*
X940275Y1408226D01*
G01X939940Y1412492D02*
X940275Y1413476D01*
G01X947982Y1376730D02*
X948652Y1377715D01*
G01X937595Y1381980D02*
X936925Y1380996D01*
G01X949322Y1375746D02*
X950327Y1377387D01*
G01X936254Y1382964D02*
X935249Y1381324D01*
G01X941615Y1412492D02*
X941280Y1411835D01*
G01X946977Y1374106D02*
X948317Y1374762D01*
G01X945971Y1375418D02*
X947982Y1376730D01*
G01X939605Y1383292D02*
X937595Y1381980D01*
G01X948317Y1374762D02*
X949322Y1375746D01*
G01X937260Y1383948D02*
X936254Y1382964D01*
G01X941951Y1392807D02*
X941615Y1392478D01*
G01X940275Y1393463D02*
X941280Y1394447D01*
G01X941951Y1398056D02*
X941615Y1397728D01*
G01X940275Y1398712D02*
X940945Y1399368D01*
G01X941951Y1407570D02*
X941615Y1407242D01*
G01X940275Y1408226D02*
X941280Y1409211D01*
G01X941951Y1412820D02*
X941615Y1412492D01*
G01X940275Y1413476D02*
X940945Y1414132D01*
G01X945971Y1373778D02*
X946977Y1374106D01*
G01X939605Y1384933D02*
X938600Y1384604D01*
G01X940945Y1399368D02*
X942621Y1400024D01*
G01X940945Y1414132D02*
X942621Y1414788D01*
G01X938600Y1384604D02*
X937260Y1383948D01*
G01X942621Y1393135D02*
X941951Y1392807D01*
G01X942621Y1398384D02*
X941951Y1398056D01*
G01X942621Y1407898D02*
X941951Y1407570D01*
G01X942621Y1413148D02*
X941951Y1412820D01*
G01X922119Y1444355D02*
G03X931961Y1454198I0J9842D01*
G01X904402Y1426796D02*
X1021332D01*
G01X931961Y1454198D02*
Y1568371D01*
G01X921922Y1511284D02*
G03I-5709J0D01*
G01X904415Y1509622D02*
X903913Y1510442D01*
G01X904583Y1508638D02*
X904415Y1509622D01*
G01X904583Y1494858D02*
Y1493874D01*
G01Y1500435D02*
Y1499451D01*
G01Y1513723D02*
Y1512903D01*
G01Y1516348D02*
Y1515527D01*
G01Y1518972D02*
Y1518152D01*
G01Y1521105D02*
Y1520285D01*
G01Y1523729D02*
Y1522909D01*
G01X904415Y1507653D02*
X904583Y1508638D01*
G01X903913Y1506833D02*
X904415Y1507653D01*
G01X931961Y1568371D02*
G03X922119Y1578213I-9842J0D01*
G01X904583Y1526354D02*
Y1525534D01*
G01X905583Y1646934D02*
Y1681186D01*
G01X984126Y1791953D02*
G03I-18701J0D01*
G01X992394Y1734079D02*
X938457D01*
G01X992394D02*
X938457D01*
G01D02*
Y1901008D01*
G01Y1734079D02*
Y1901008D01*
G01X905583Y1774631D02*
Y1808883D01*
G01X980583Y1791953D02*
G03I-15158J0D01*
G01X981173D02*
G03I-15748J0D01*
G01X980583Y1867150D02*
G03I-15158J0D01*
G01X981173D02*
G03I-15748J0D01*
G01X984126D02*
G03I-18701J0D01*
G01X922119Y1877583D02*
G03X931961Y1887426I-1J9843D01*
G01X938457Y1901008D02*
X992394D01*
G01X938457D02*
X992394D01*
G01X931961Y1887426D02*
Y2001599D01*
G01X937867Y1977190D02*
G03X941804Y1973253I3937J0D01*
G01X937867Y1977190D02*
G03X941804Y1973253I3937J0D01*
G01X921922Y1944513D02*
G03I-5709J0D01*
G01X941804Y1973253D02*
X1071725D01*
G01X941804D02*
X1071725D01*
G01X937867Y2008686D02*
Y1977190D01*
G01Y2008686D02*
Y1977190D01*
G01Y2008686D02*
G03X933930Y2012623I-3937J0D01*
G01X937867Y2008686D02*
G03X933930Y2012623I-3937J0D01*
G01X931961Y2001599D02*
G03X922119Y2011442I-9842J1D01*
G01X1004876Y153528D02*
Y383528D01*
G01X1003576Y152032D02*
Y385024D01*
G01X994678D02*
Y152032D01*
G01X993378Y182028D02*
Y355028D01*
G01X963378Y153528D02*
Y189528D01*
G01D02*
Y190028D01*
G01X955478Y194528D02*
Y187528D01*
G01X963378Y190028D02*
X993378D01*
G01X963378Y189528D02*
X993378D01*
G01X1004876Y183528D02*
X1032276D01*
G01X993378Y182028D02*
X963378D01*
G01X1004876Y153528D02*
X1032276D01*
G01X1063576Y152032D02*
X1003576D01*
G01X981408Y227028D02*
G03X977948I-1730J-1019D01*
G01X977926Y235028D02*
G03X981430I1752J981D01*
G01X977948Y227028D02*
G03X981408I1730J-1019D01*
G01X981430Y235028D02*
G03X977926I-1752J981D01*
G01X981408Y207028D02*
G03X977948I-1730J-1019D01*
G01X977926Y215028D02*
G03X981430I1752J981D01*
G01X977948Y207028D02*
G03X981408I1730J-1019D01*
G01X981430Y215028D02*
G03X977926I-1752J981D01*
G01X971408Y227028D02*
G03X967948I-1730J-1019D01*
G01X967926Y235028D02*
G03X971430I1752J981D01*
G01X967948Y227028D02*
G03X971408I1730J-1019D01*
G01X971430Y235028D02*
G03X967926I-1752J981D01*
G01X971408Y207028D02*
G03X967948I-1730J-1019D01*
G01X967926Y215028D02*
G03X971430I1752J981D01*
G01X967948Y207028D02*
G03X971408I1730J-1019D01*
G01X971430Y215028D02*
G03X967926I-1752J981D01*
G01X961408Y207028D02*
G03X957948I-1730J-1019D01*
G01X961408Y227028D02*
G03X957948I-1730J-1019D01*
G01X957926Y215028D02*
G03X961430I1752J981D01*
G01X957926Y235028D02*
G03X961430I1752J981D01*
G01X957948Y207028D02*
G03X961408I1730J-1019D01*
G01X957948Y227028D02*
G03X961408I1730J-1019D01*
G01X961430Y215028D02*
G03X957926I-1752J981D01*
G01X961430Y235028D02*
G03X957926I-1752J981D01*
G01X990378Y342528D02*
Y194528D01*
G01X988378Y198528D02*
Y243528D01*
G01X988178D02*
Y293528D01*
G01X982308Y215028D02*
Y207028D01*
G01Y235028D02*
Y227028D01*
G01X980928Y235028D02*
Y237028D01*
G01Y225028D02*
Y227028D01*
G01Y215028D02*
Y217028D01*
G01Y205028D02*
Y207028D01*
G01X978428D02*
Y205028D01*
G01Y217028D02*
Y215028D01*
G01Y227028D02*
Y225028D01*
G01Y237028D02*
Y235028D01*
G01X978384Y207028D02*
Y205028D01*
G01Y217028D02*
Y215028D01*
G01Y227028D02*
Y225028D01*
G01Y237028D02*
Y235028D01*
G01X973591Y207028D02*
Y205028D01*
G01Y217028D02*
Y215028D01*
G01Y227028D02*
Y225028D01*
G01Y237028D02*
Y235028D01*
G01X970928D02*
Y237028D01*
G01Y225028D02*
Y227028D01*
G01Y215028D02*
Y217028D01*
G01Y205028D02*
Y207028D01*
G01X968428D02*
Y205028D01*
G01Y217028D02*
Y215028D01*
G01Y227028D02*
Y225028D01*
G01Y237028D02*
Y235028D01*
G01X960928D02*
Y237028D01*
G01Y225028D02*
Y227028D01*
G01Y215028D02*
Y217028D01*
G01Y205028D02*
Y207028D01*
G01X958428D02*
Y205028D01*
G01Y217028D02*
Y215028D01*
G01Y227028D02*
Y225028D01*
G01Y237028D02*
Y235028D01*
G01X988178Y243528D02*
X990373D01*
G01X980928Y237028D02*
X978428D01*
G01Y225028D02*
X980928D01*
G01Y217028D02*
X978428D01*
G01Y205028D02*
X980928D01*
G01X990378Y194528D02*
X955478D01*
G01X981686Y248528D02*
G03I-2008J0D01*
G01Y258528D02*
G03I-2008J0D01*
G01Y268528D02*
G03I-2008J0D01*
G01Y278528D02*
G03I-2008J0D01*
G01Y288528D02*
G03I-2008J0D01*
G01X971686Y248528D02*
G03I-2008J0D01*
G01Y258528D02*
G03I-2008J0D01*
G01Y268528D02*
G03I-2008J0D01*
G01Y278528D02*
G03I-2008J0D01*
G01Y288528D02*
G03I-2008J0D01*
G01X961686Y268528D02*
G03I-2008J0D01*
G01Y278528D02*
G03I-2008J0D01*
G01Y288528D02*
G03I-2008J0D01*
G01Y248528D02*
G03I-2008J0D01*
G01Y258528D02*
G03I-2008J0D01*
G01X980928Y249778D02*
X981318Y250169D01*
G01X978428Y247278D02*
X978037Y246888D01*
G01X980928Y259778D02*
X981318Y260169D01*
G01X968037Y246888D02*
X968428Y247278D01*
G01X971318Y250169D02*
X970928Y249778D01*
G01X978428Y257278D02*
X978037Y256888D01*
G01X980928Y269778D02*
X981318Y270169D01*
G01X968037Y256888D02*
X968428Y257278D01*
G01X958037Y246888D02*
X958428Y247278D01*
G01X961318Y250169D02*
X960928Y249778D01*
G01X971318Y260169D02*
X970928Y259778D01*
G01X978428Y267278D02*
X978037Y266888D01*
G01X980928Y279778D02*
X981318Y280169D01*
G01X968037Y266888D02*
X968428Y267278D01*
G01X958037Y256888D02*
X958428Y257278D01*
G01X961318Y260169D02*
X960928Y259778D01*
G01X971318Y270169D02*
X970928Y269778D01*
G01X978428Y277278D02*
X978037Y276888D01*
G01X980928Y289778D02*
X981318Y290169D01*
G01X968037Y276888D02*
X968428Y277278D01*
G01X958037Y266888D02*
X958428Y267278D01*
G01X961318Y270169D02*
X960928Y269778D01*
G01X971318Y280169D02*
X970928Y279778D01*
G01X978428Y287278D02*
X978037Y286888D01*
G01X968037D02*
X968428Y287278D01*
G01X958037Y276888D02*
X958428Y277278D01*
G01X961318Y280169D02*
X960928Y279778D01*
G01X971318Y290169D02*
X970928Y289778D01*
G01X958037Y286888D02*
X958428Y287278D01*
G01X961318Y290169D02*
X960928Y289778D01*
G01X988378Y293528D02*
Y338528D01*
G01X981318Y286888D02*
Y290169D01*
G01Y276888D02*
Y280169D01*
G01Y266888D02*
Y270169D01*
G01Y256888D02*
Y260169D01*
G01Y246888D02*
Y250169D01*
G01X981058Y249908D02*
Y247148D01*
G01Y259908D02*
Y257148D01*
G01Y269908D02*
Y267148D01*
G01Y279908D02*
Y277148D01*
G01Y289908D02*
Y287148D01*
G01X980928Y249778D02*
Y247278D01*
G01Y259778D02*
Y257278D01*
G01Y269778D02*
Y267278D01*
G01Y279778D02*
Y277278D01*
G01Y289778D02*
Y287278D01*
G01X978428Y249778D02*
Y247278D01*
G01Y259778D02*
Y257278D01*
G01Y269778D02*
Y267278D01*
G01Y279778D02*
Y277278D01*
G01Y289778D02*
Y287278D01*
G01X978298Y249908D02*
Y247148D01*
G01Y259908D02*
Y257148D01*
G01Y269908D02*
Y267148D01*
G01Y279908D02*
Y277148D01*
G01Y289908D02*
Y287148D01*
G01X978037Y250169D02*
Y246888D01*
G01Y260169D02*
Y256888D01*
G01Y270169D02*
Y266888D01*
G01Y280169D02*
Y276888D01*
G01Y290169D02*
Y286888D01*
G01X971318Y250169D02*
Y246888D01*
G01Y260169D02*
Y256888D01*
G01Y270169D02*
Y266888D01*
G01Y280169D02*
Y276888D01*
G01Y290169D02*
Y286888D01*
G01X971058Y249908D02*
Y247148D01*
G01Y259908D02*
Y257148D01*
G01Y269908D02*
Y267148D01*
G01Y279908D02*
Y277148D01*
G01Y289908D02*
Y287148D01*
G01X970928Y249778D02*
Y247278D01*
G01Y259778D02*
Y257278D01*
G01Y269778D02*
Y267278D01*
G01Y279778D02*
Y277278D01*
G01Y289778D02*
Y287278D01*
G01X968428D02*
Y289778D01*
G01Y277278D02*
Y279778D01*
G01Y267278D02*
Y269778D01*
G01Y257278D02*
Y259778D01*
G01Y247278D02*
Y249778D01*
G01X968298Y287148D02*
Y289908D01*
G01Y277148D02*
Y279908D01*
G01Y267148D02*
Y269908D01*
G01Y257148D02*
Y259908D01*
G01Y247148D02*
Y249908D01*
G01X968037Y286888D02*
Y290169D01*
G01Y276888D02*
Y280169D01*
G01Y266888D02*
Y270169D01*
G01Y256888D02*
Y260169D01*
G01Y246888D02*
Y250169D01*
G01X961318D02*
Y246888D01*
G01Y260169D02*
Y256888D01*
G01Y270169D02*
Y266888D01*
G01Y280169D02*
Y276888D01*
G01Y290169D02*
Y286888D01*
G01X961058Y249908D02*
Y247148D01*
G01Y259908D02*
Y257148D01*
G01Y269908D02*
Y267148D01*
G01Y279908D02*
Y277148D01*
G01Y289908D02*
Y287148D01*
G01X960928Y249778D02*
Y247278D01*
G01Y259778D02*
Y257278D01*
G01Y269778D02*
Y267278D01*
G01Y279778D02*
Y277278D01*
G01Y289778D02*
Y287278D01*
G01X958428D02*
Y289778D01*
G01Y277278D02*
Y279778D01*
G01Y267278D02*
Y269778D01*
G01Y257278D02*
Y259778D01*
G01Y247278D02*
Y249778D01*
G01X958298Y287148D02*
Y289908D01*
G01Y277148D02*
Y279908D01*
G01Y267148D02*
Y269908D01*
G01Y257148D02*
Y259908D01*
G01Y247148D02*
Y249908D01*
G01X958037Y286888D02*
Y290169D01*
G01Y276888D02*
Y280169D01*
G01Y266888D02*
Y270169D01*
G01Y256888D02*
Y260169D01*
G01Y246888D02*
Y250169D01*
G01X980928Y287278D02*
X981318Y286888D01*
G01X978037Y290169D02*
X978428Y289778D01*
G01X980928Y277278D02*
X981318Y276888D01*
G01X978037Y280169D02*
X978428Y279778D01*
G01X970928Y287278D02*
X971318Y286888D01*
G01X968037Y290169D02*
X968428Y289778D01*
G01X980928Y267278D02*
X981318Y266888D01*
G01X978037Y270169D02*
X978428Y269778D01*
G01X970928Y277278D02*
X971318Y276888D01*
G01X968037Y280169D02*
X968428Y279778D01*
G01X960928Y287278D02*
X961318Y286888D01*
G01X958037Y290169D02*
X958428Y289778D01*
G01X980928Y257278D02*
X981318Y256888D01*
G01X978037Y260169D02*
X978428Y259778D01*
G01X970928Y267278D02*
X971318Y266888D01*
G01X968037Y270169D02*
X968428Y269778D01*
G01X960928Y277278D02*
X961318Y276888D01*
G01X958037Y280169D02*
X958428Y279778D01*
G01X980928Y247278D02*
X981318Y246888D01*
G01X978037Y250169D02*
X978428Y249778D01*
G01X970928Y257278D02*
X971318Y256888D01*
G01X968037Y260169D02*
X968428Y259778D01*
G01X960928Y267278D02*
X961318Y266888D01*
G01X958037Y270169D02*
X958428Y269778D01*
G01X970928Y247278D02*
X971318Y246888D01*
G01X968037Y250169D02*
X968428Y249778D01*
G01X960928Y257278D02*
X961318Y256888D01*
G01X958037Y260169D02*
X958428Y259778D01*
G01X960928Y247278D02*
X961318Y246888D01*
G01X958037Y250169D02*
X958428Y249778D01*
G01X988178Y293528D02*
X990373D01*
G01X968037Y290169D02*
X971318D01*
G01X958037D02*
X961318D01*
G01X981318D02*
X978037D01*
G01X978298Y289908D02*
X981058D01*
G01X968298D02*
X971058D01*
G01X958298D02*
X961058D01*
G01X978428Y289778D02*
X980928D01*
G01X968428D02*
X970928D01*
G01X958428D02*
X960928D01*
G01Y287278D02*
X958428D01*
G01X970928D02*
X968428D01*
G01X980928D02*
X978428D01*
G01X961058Y287148D02*
X958298D01*
G01X971058D02*
X968298D01*
G01X981058D02*
X978298D01*
G01X978037Y286888D02*
X981318D01*
G01X961318D02*
X958037D01*
G01X971318D02*
X968037D01*
G01Y280169D02*
X971318D01*
G01X958037D02*
X961318D01*
G01X981318D02*
X978037D01*
G01X978298Y279908D02*
X981058D01*
G01X968298D02*
X971058D01*
G01X958298D02*
X961058D01*
G01X978428Y279778D02*
X980928D01*
G01X968428D02*
X970928D01*
G01X958428D02*
X960928D01*
G01Y277278D02*
X958428D01*
G01X970928D02*
X968428D01*
G01X980928D02*
X978428D01*
G01X961058Y277148D02*
X958298D01*
G01X971058D02*
X968298D01*
G01X981058D02*
X978298D01*
G01X978037Y276888D02*
X981318D01*
G01X961318D02*
X958037D01*
G01X971318D02*
X968037D01*
G01Y270169D02*
X971318D01*
G01X958037D02*
X961318D01*
G01X981318D02*
X978037D01*
G01X978298Y269908D02*
X981058D01*
G01X968298D02*
X971058D01*
G01X958298D02*
X961058D01*
G01X978428Y269778D02*
X980928D01*
G01X968428D02*
X970928D01*
G01X958428D02*
X960928D01*
G01Y267278D02*
X958428D01*
G01X970928D02*
X968428D01*
G01X980928D02*
X978428D01*
G01X961058Y267148D02*
X958298D01*
G01X971058D02*
X968298D01*
G01X981058D02*
X978298D01*
G01X978037Y266888D02*
X981318D01*
G01X961318D02*
X958037D01*
G01X971318D02*
X968037D01*
G01Y260169D02*
X971318D01*
G01X958037D02*
X961318D01*
G01X981318D02*
X978037D01*
G01X978298Y259908D02*
X981058D01*
G01X968298D02*
X971058D01*
G01X958298D02*
X961058D01*
G01X978428Y259778D02*
X980928D01*
G01X968428D02*
X970928D01*
G01X958428D02*
X960928D01*
G01Y257278D02*
X958428D01*
G01X970928D02*
X968428D01*
G01X980928D02*
X978428D01*
G01X961058Y257148D02*
X958298D01*
G01X971058D02*
X968298D01*
G01X981058D02*
X978298D01*
G01X978037Y256888D02*
X981318D01*
G01X961318D02*
X958037D01*
G01X971318D02*
X968037D01*
G01Y250169D02*
X971318D01*
G01X958037D02*
X961318D01*
G01X981318D02*
X978037D01*
G01X978298Y249908D02*
X981058D01*
G01X968298D02*
X971058D01*
G01X958298D02*
X961058D01*
G01X978428Y249778D02*
X980928D01*
G01X968428D02*
X970928D01*
G01X958428D02*
X960928D01*
G01Y247278D02*
X958428D01*
G01X970928D02*
X968428D01*
G01X980928D02*
X978428D01*
G01X961058Y247148D02*
X958298D01*
G01X971058D02*
X968298D01*
G01X981058D02*
X978298D01*
G01X978037Y246888D02*
X981318D01*
G01X961318D02*
X958037D01*
G01X971318D02*
X968037D01*
G01X981430Y302029D02*
G03X977926I-1752J-981D01*
G01X981430Y322029D02*
G03X977926I-1752J-981D01*
G01X977948Y310028D02*
G03X981408I1730J1020D01*
G01X977948Y330028D02*
G03X981408I1730J1020D01*
G01X977926Y302029D02*
G03X981430I1752J-981D01*
G01X977926Y322029D02*
G03X981430I1752J-981D01*
G01X981408Y310028D02*
G03X977948I-1730J1020D01*
G01X981408Y330028D02*
G03X977948I-1730J1020D01*
G01X971430Y302029D02*
G03X967926I-1752J-981D01*
G01X971430Y322029D02*
G03X967926I-1752J-981D01*
G01X967948Y310028D02*
G03X971408I1730J1020D01*
G01X967948Y330028D02*
G03X971408I1730J1020D01*
G01X967926Y302029D02*
G03X971430I1752J-981D01*
G01X967926Y322029D02*
G03X971430I1752J-981D01*
G01X971408Y310028D02*
G03X967948I-1730J1020D01*
G01X971408Y330028D02*
G03X967948I-1730J1020D01*
G01X961430Y322029D02*
G03X957926I-1752J-981D01*
G01X957948Y330028D02*
G03X961408I1730J1020D01*
G01X957926Y322029D02*
G03X961430I1752J-981D01*
G01X961408Y330028D02*
G03X957948I-1730J1020D01*
G01X961430Y302029D02*
G03X957926I-1752J-981D01*
G01X957948Y310028D02*
G03X961408I1730J1020D01*
G01X957926Y302029D02*
G03X961430I1752J-981D01*
G01X961408Y310028D02*
G03X957948I-1730J1020D01*
G01X982308D02*
Y302028D01*
G01Y330028D02*
Y322028D01*
G01X980928Y330028D02*
Y332028D01*
G01Y320028D02*
Y322028D01*
G01Y310028D02*
Y312028D01*
G01Y300028D02*
Y302028D01*
G01X978428D02*
Y300028D01*
G01Y312028D02*
Y310028D01*
G01Y322028D02*
Y320028D01*
G01Y332028D02*
Y330028D01*
G01X978384Y302028D02*
Y300028D01*
G01Y312028D02*
Y310028D01*
G01Y322028D02*
Y320028D01*
G01Y332028D02*
Y330028D01*
G01X973591Y302028D02*
Y300028D01*
G01Y312028D02*
Y310028D01*
G01Y322028D02*
Y320028D01*
G01Y332028D02*
Y330028D01*
G01X970928D02*
Y332028D01*
G01Y320028D02*
Y322028D01*
G01Y310028D02*
Y312028D01*
G01Y300028D02*
Y302028D01*
G01X968428D02*
Y300028D01*
G01Y312028D02*
Y310028D01*
G01Y322028D02*
Y320028D01*
G01Y332028D02*
Y330028D01*
G01X963378Y347528D02*
Y383528D01*
G01Y347028D02*
Y347528D01*
G01X960928Y330028D02*
Y332028D01*
G01Y320028D02*
Y322028D01*
G01Y310028D02*
Y312028D01*
G01Y300028D02*
Y302028D01*
G01X958428D02*
Y300028D01*
G01Y312028D02*
Y310028D01*
G01Y322028D02*
Y320028D01*
G01Y332028D02*
Y330028D01*
G01X955478Y349528D02*
Y342528D01*
G01X993378Y347528D02*
X963378D01*
G01X993378Y347028D02*
X963378D01*
G01X955478Y342528D02*
X990378D01*
G01X980928Y332028D02*
X978428D01*
G01Y320028D02*
X980928D01*
G01Y312028D02*
X978428D01*
G01Y300028D02*
X980928D01*
G01X1003576Y385024D02*
X1063576D01*
G01X1032276Y383528D02*
X1004876D01*
G01X963378Y355028D02*
X993378D01*
G01X1032276Y353528D02*
X1004876D01*
G01X983143Y611442D02*
Y611343D01*
G01X982355D02*
Y611442D01*
G01X982158Y612190D02*
Y610300D01*
G01Y619670D02*
Y617780D01*
G01X981568Y612190D02*
Y610300D01*
G01Y619670D02*
Y617780D01*
G01X981374Y612190D02*
Y610300D01*
G01Y619670D02*
Y617780D01*
G01X981240Y612190D02*
Y610300D01*
G01Y619670D02*
Y617780D01*
G01X980792Y612190D02*
Y610300D01*
G01Y619670D02*
Y617780D01*
G01X980658Y612190D02*
Y610300D01*
G01Y619670D02*
Y617780D01*
G01X980464Y612190D02*
Y610300D01*
G01Y619670D02*
Y617780D01*
G01X979993Y609080D02*
Y620891D01*
G01X974481D02*
Y609080D01*
G01X974010Y615930D02*
Y614040D01*
G01X973816Y615930D02*
Y614040D01*
G01X973682Y615930D02*
Y614040D01*
G01X973234Y615930D02*
Y614040D01*
G01X973100Y615930D02*
Y614040D01*
G01X972906Y615930D02*
Y614040D01*
G01X972316Y615930D02*
Y614040D01*
G01X982489Y611343D02*
X982606Y611245D01*
G01X982472D02*
X982355Y611343D01*
G01X979993Y620891D02*
X974481D01*
G01X982158Y619670D02*
X979993D01*
G01X982158Y617780D02*
X979993D01*
G01X974481Y615930D02*
X972316D01*
G01X974481Y614040D02*
X972316D01*
G01X982158Y612190D02*
X979993D01*
G01X982355Y611442D02*
X983143D01*
G01Y611343D02*
X982489D01*
G01X982606Y611245D02*
X982472D01*
G01X982158Y610300D02*
X979993D01*
G01X974481Y609080D02*
X979993D01*
G01X998179Y977518D02*
Y954552D01*
G01X993153D02*
Y977518D01*
G01X977237Y949631D02*
Y954552D01*
G01X998179D02*
X1016607D01*
G01X977237D02*
X993153D01*
G01X1016607Y949631D02*
X977237D01*
G01X990640Y1006225D02*
X996503Y994742D01*
G01Y989001D02*
X988127Y1004585D01*
G01D02*
X990640Y1006225D01*
G01X1004880Y1004585D02*
X996503Y989001D01*
G01Y994742D02*
X1002367Y1006225D01*
G01X977237Y977518D02*
Y982439D01*
G01X1002367Y1006225D02*
X1004880Y1004585D01*
G01X977237Y982439D02*
X1016607D01*
G01X993153Y977518D02*
X977237D01*
G01X1016607D02*
X998179D01*
G01X991477Y1042314D02*
X992315Y1038213D01*
G01X977237Y1042314D02*
X978075Y1038213D01*
G01X995666Y1041494D02*
X996503Y1039034D01*
G01X982263D02*
X981425Y1041494D01*
G01X978075Y1038213D02*
X980588Y1034112D01*
G01X996503Y1039034D02*
X998179Y1036573D01*
G01X992315Y1038213D02*
X995666Y1033292D01*
G01X983938Y1036573D02*
X982263Y1039034D01*
G01X998179Y1036573D02*
X999854Y1034933D01*
G01X980588Y1034112D02*
X983938Y1031652D01*
G01X986451Y1034933D02*
X983938Y1036573D01*
G01X1009906Y1057078D02*
X1005718Y1058719D01*
G01X983938Y1031652D02*
X988127Y1030011D01*
G01X1007393Y1053797D02*
X1004880Y1054618D01*
G01X999854Y1034933D02*
X1002367Y1034112D01*
G01X988964D02*
X986451Y1034933D01*
G01X993990Y1033292D02*
X988964Y1034112D01*
G01X1005718Y1058719D02*
X1001529D01*
G01X1004880Y1054618D02*
X1002367D01*
G01X1005718Y1030011D02*
X1009906Y1031652D01*
G01X999854Y1053797D02*
X998179Y1052157D01*
G01D02*
X996503Y1049696D01*
G01X994828Y1054618D02*
X992315Y1050517D01*
G01X996503Y1049696D02*
X995666Y1047236D01*
G01X981425Y1046415D02*
X982263Y1048876D01*
G01X992315Y1050517D02*
X991477Y1046415D01*
G01X978075Y1049696D02*
X977237Y1045595D01*
G01X995666Y1047236D02*
Y1041494D01*
G01X991477Y1046415D02*
Y1042314D01*
G01X986451Y1052977D02*
Y1057078D01*
G01X981425Y1041494D02*
Y1046415D01*
G01X977237Y1017708D02*
Y1022629D01*
G01Y1045595D02*
Y1042314D01*
G01X983938Y1017708D02*
X989802Y1012787D01*
G01X983101D02*
X977237Y1017708D01*
G01X988127Y1030011D02*
X993990Y1029191D01*
G01X1002367Y1034112D02*
X1004880D01*
G01X995666Y1033292D02*
X993990D01*
G01Y1029191D02*
X999854D01*
G01X977237Y1022629D02*
X1016607D01*
G01Y1017708D02*
X983938D01*
G01X989802Y1012787D02*
X983101D01*
G01X999854Y1029191D02*
X1005718Y1030011D01*
G01X1004880Y1034112D02*
X1007393Y1034933D01*
G01X1002367Y1054618D02*
X999854Y1053797D01*
G01X986451Y1057078D02*
X983938Y1056258D01*
G01X1001529Y1058719D02*
X997341Y1057078D01*
G01X983938Y1051337D02*
X986451Y1052977D01*
G01X983938Y1056258D02*
X980588Y1053797D01*
G01X997341Y1057078D02*
X994828Y1054618D01*
G01X982263Y1048876D02*
X983938Y1051337D01*
G01X980588Y1053797D02*
X978075Y1049696D01*
G01X993990Y1107931D02*
X995666Y1106291D01*
G01X992315D02*
X990640Y1107931D01*
G01X995666Y1106291D02*
X1016607D01*
G01X989802D02*
X992315D01*
G01X993153Y1110392D02*
X993990Y1107931D01*
G01X990640D02*
X989802Y1110392D01*
G01X990640Y1084145D02*
X989802Y1086606D01*
G01X993153Y1073482D02*
X993990Y1071022D01*
G01X990640D02*
X989802Y1073482D01*
G01X993153Y1085786D02*
X993990Y1084145D01*
G01D02*
X994828Y1083325D01*
G01X993153Y1081684D02*
X990640Y1084145D01*
G01X993990Y1071022D02*
X995666Y1069381D01*
G01X992315D02*
X990640Y1071022D01*
G01X994828Y1083325D02*
X996503Y1082505D01*
G01X1016607Y1102190D02*
X989802D01*
G01X996503Y1095628D02*
X1016607D01*
G01Y1091527D02*
X996503D01*
G01Y1082505D02*
X1016607D01*
G01Y1078404D02*
X996503D01*
G01X995666Y1069381D02*
X1016607D01*
G01X989802D02*
X992315D01*
G01X1016607Y1065280D02*
X989802D01*
G01Y1076763D02*
X990640Y1079224D01*
G01X993153Y1075123D02*
Y1073482D01*
G01Y1088246D02*
Y1085786D01*
G01Y1112032D02*
Y1110392D01*
G01X989802D02*
Y1113673D01*
G01Y1102190D02*
Y1106291D01*
G01Y1086606D02*
Y1089887D01*
G01Y1073482D02*
Y1076763D01*
G01Y1065280D02*
Y1069381D01*
G01X992315Y1093988D02*
X996503Y1095628D01*
G01Y1078404D02*
X994828Y1077583D01*
G01X996503Y1091527D02*
X994828Y1090707D01*
G01Y1077583D02*
X993990Y1076763D01*
G01X990640Y1079224D02*
X993153Y1081684D01*
G01X994828Y1090707D02*
X993990Y1089887D01*
G01X990640Y1092347D02*
X992315Y1093988D01*
G01X994828Y1114493D02*
X993990Y1113673D01*
G01Y1076763D02*
X993153Y1075123D01*
G01X993990Y1089887D02*
X993153Y1088246D01*
G01X993990Y1113673D02*
X993153Y1112032D01*
G01X989802Y1089887D02*
X990640Y1092347D01*
G01X989802Y1113673D02*
X990640Y1116133D01*
G01X996503Y1115313D02*
X994828Y1114493D01*
G01X993990Y1121055D02*
X994828Y1120234D01*
G01X993153Y1118594D02*
X990640Y1121055D01*
G01X994828Y1120234D02*
X996503Y1119414D01*
G01Y1132538D02*
X1016607D01*
G01Y1128436D02*
X996503D01*
G01Y1119414D02*
X1016607D01*
G01Y1115313D02*
X996503D01*
G01X990640Y1121055D02*
X989802Y1123515D01*
G01X993153Y1122695D02*
X993990Y1121055D01*
G01X993153Y1125156D02*
Y1122695D01*
G01X989802Y1123515D02*
Y1126796D01*
G01X990640Y1116133D02*
X993153Y1118594D01*
G01X994828Y1127616D02*
X993990Y1126796D01*
G01X990640Y1129257D02*
X992315Y1130897D01*
G01X993990Y1126796D02*
X993153Y1125156D01*
G01X989802Y1126796D02*
X990640Y1129257D01*
G01X992315Y1130897D02*
X996503Y1132538D01*
G01Y1128436D02*
X994828Y1127616D01*
G01X979993Y1309867D02*
X974481D01*
G01X982158Y1308646D02*
X979993D01*
G01X982158Y1306757D02*
X979993D01*
G01X974481Y1304906D02*
X972316D01*
G01X974481Y1303017D02*
X972316D01*
G01X982489Y1300320D02*
X982606Y1300221D01*
G01X982472D02*
X982355Y1300320D01*
G01X982158Y1301166D02*
X979993D01*
G01X982355Y1300418D02*
X983143D01*
G01Y1300320D02*
X982489D01*
G01X982606Y1300221D02*
X982472D01*
G01X982158Y1299276D02*
X979993D01*
G01X974481Y1298056D02*
X979993D01*
G01X983143Y1300418D02*
Y1300320D01*
G01X982355D02*
Y1300418D01*
G01X982158Y1301166D02*
Y1299276D01*
G01Y1308646D02*
Y1306757D01*
G01X981568Y1301166D02*
Y1299276D01*
G01Y1308646D02*
Y1306757D01*
G01X981374Y1301166D02*
Y1299276D01*
G01Y1308646D02*
Y1306757D01*
G01X981240Y1301166D02*
Y1299276D01*
G01Y1308646D02*
Y1306757D01*
G01X980792Y1301166D02*
Y1299276D01*
G01Y1308646D02*
Y1306757D01*
G01X980658Y1301166D02*
Y1299276D01*
G01Y1308646D02*
Y1306757D01*
G01X980464Y1301166D02*
Y1299276D01*
G01Y1308646D02*
Y1306757D01*
G01X979993Y1298056D02*
Y1309867D01*
G01X974481D02*
Y1298056D01*
G01X974010Y1304906D02*
Y1303017D01*
G01X973816Y1304906D02*
Y1303017D01*
G01X973682Y1304906D02*
Y1303017D01*
G01X973234Y1304906D02*
Y1303017D01*
G01X973100Y1304906D02*
Y1303017D01*
G01X972906Y1304906D02*
Y1303017D01*
G01X972316Y1304906D02*
Y1303017D01*
G01X1057354Y1734079D02*
X1003417D01*
G01X1057354D02*
X1003417D01*
G01D02*
Y1816244D01*
G01Y1734079D02*
Y1816244D01*
G01X992394D02*
Y1734079D01*
G01Y1816244D02*
Y1734079D01*
G01X973299Y1791953D02*
G03I-7874J0D01*
G01X973890D02*
G03I-8465J0D01*
G01X974284D02*
G03I-8859J0D01*
G01X974874D02*
G03I-9449J0D01*
G01X975169D02*
G03I-9744J0D01*
G01X975268D02*
G03I-9843J0D01*
G01D02*
G03I-9843J0D01*
G01X988063Y1829630D02*
G03Y1816244I0J-6693D01*
G01Y1829630D02*
G03Y1816244I0J-6693D01*
G01X1003417D02*
X1007748D01*
G01X1003417D02*
X1007748D01*
G01X992394D02*
X988063D01*
G01X992394D02*
X988063D01*
G01X1003417Y1814000D02*
X1016843D01*
G01X992394D02*
X1003417D01*
G01X978969D02*
X992394D01*
G01X978969Y1831874D02*
Y1814000D01*
G01X1003417Y1829630D02*
X1007748D01*
G01X1003417D02*
X1007748D01*
G01X992394D02*
X988063D01*
G01X992394D02*
X988063D01*
G01X1003417D02*
Y1901008D01*
G01Y1829630D02*
Y1901008D01*
G01X992394D02*
Y1829630D01*
G01Y1901008D02*
Y1829630D01*
G01X983816Y1827938D02*
X982907Y1826363D01*
G01X991997Y1827938D02*
X983816D01*
G01X982907Y1826363D02*
Y1819513D01*
G01X985569Y1823690D02*
X985752D01*
G01Y1822230D02*
X985569D01*
G01X986647Y1821678D02*
X989166D01*
G01X986647Y1824198D02*
Y1821678D01*
G01X985752Y1823690D02*
Y1822230D01*
G01X985569D02*
Y1823442D01*
G01X985387Y1823224D02*
Y1823473D01*
G01X985569Y1823442D02*
X985387Y1823224D01*
G01Y1823473D02*
X985569Y1823690D01*
G01X989166Y1824198D02*
X986647D01*
G01X989166Y1821678D02*
Y1824198D01*
G01X989875Y1822938D02*
G03I-1968J0D01*
G01X982907Y1819513D02*
X983816Y1817938D01*
G01X993816D02*
X1001997D01*
G01X983816D02*
X991997D01*
G01X992907Y1819513D02*
X993816Y1817938D01*
G01X991997D02*
X992907Y1819513D01*
G01X1001997Y1827938D02*
X993816D01*
G01X999166Y1821678D02*
Y1824198D01*
G01X999875Y1822938D02*
G03I-1968J0D01*
G01X999166Y1824198D02*
X996647D01*
G01Y1821678D02*
X999166D01*
G01X992907Y1826363D02*
X991997Y1827938D01*
G01X996647Y1824198D02*
Y1821678D01*
G01X993816Y1827938D02*
X992907Y1826363D01*
G01X1002907D02*
X1001997Y1827938D01*
G01X1009875Y1822938D02*
G03I-1968J0D01*
G01X1002907Y1819513D02*
X1003816Y1817938D01*
G01X1001997D02*
X1002907Y1819513D01*
G01X1003816Y1817938D02*
X1011997D01*
G01Y1827938D02*
X1003816D01*
G01D02*
X1002907Y1826363D01*
G01X973299Y1867150D02*
G03I-7874J0D01*
G01X973890D02*
G03I-8465J0D01*
G01X974284D02*
G03I-8859J0D01*
G01X974874D02*
G03I-9449J0D01*
G01X975169D02*
G03I-9744J0D01*
G01X975268D02*
G03I-9843J0D01*
G01D02*
G03I-9843J0D01*
G01X992394Y1831874D02*
X978969D01*
G01X1003417D02*
X992394D01*
G01X1016843D02*
X1003417D01*
G01Y1901008D02*
X1057354D01*
G01X1003417D02*
X1057354D01*
G01X1010110Y-65085D02*
Y-84022D01*
G01X1045938Y-33677D02*
X1037277D01*
X1043484Y-37683D01*
Y-32269D01*
G01X1044639Y-28697D02*
X1045361Y-28047D01*
X1045794Y-27289D01*
X1045938Y-26315D01*
X1045649Y-25341D01*
X1045072Y-24583D01*
X1044062Y-24041D01*
X1042907Y-23933D01*
X1041752Y-24150D01*
X1041030Y-24691D01*
X1040453Y-25449D01*
X1040308Y-26207D01*
X1040453Y-26965D01*
X1041030Y-27939D01*
X1037277Y-27614D01*
Y-24691D01*
G01X1046227Y-17654D02*
X1046082Y-17871D01*
X1045794D01*
X1045649Y-17654D01*
X1045794Y-17437D01*
X1046082D01*
X1046227Y-17654D01*
G01X1044639Y-11375D02*
X1045361Y-10725D01*
X1045794Y-9967D01*
X1045938Y-8993D01*
X1045649Y-8019D01*
X1045072Y-7261D01*
X1044062Y-6719D01*
X1042907Y-6611D01*
X1041752Y-6828D01*
X1041030Y-7369D01*
X1040453Y-8127D01*
X1040308Y-8885D01*
X1040453Y-9643D01*
X1041030Y-10617D01*
X1037277Y-10292D01*
Y-7369D01*
G01Y-332D02*
X1037566Y-1198D01*
X1038287Y-1848D01*
X1039153Y-2281D01*
X1040308Y-2606D01*
X1041608Y-2714D01*
X1042907Y-2606D01*
X1044062Y-2281D01*
X1044928Y-1848D01*
X1045649Y-1198D01*
X1045938Y-332D01*
X1045649Y534D01*
X1044928Y1184D01*
X1044062Y1617D01*
X1042907Y1942D01*
X1041608Y2050D01*
X1040308Y1942D01*
X1039153Y1617D01*
X1038287Y1184D01*
X1037566Y534D01*
X1037277Y-332D01*
G01X1054993Y122859D02*
G03I-6890J0D01*
G01X1063851D02*
G03I-15748J0D01*
G01X1023477Y183528D02*
G03I-4901J0D01*
G01X1024676Y163528D02*
G03I-6100J0D01*
G01X1024835D02*
G03I-6259J0D01*
G01X1032276Y153528D02*
Y189528D01*
G01D02*
Y190028D01*
G01X1024376Y194528D02*
Y187528D01*
G01X1019926Y188478D02*
Y178578D01*
G01X1017226D02*
Y188478D01*
G01X1007876Y187528D02*
Y349528D01*
G01X1032276Y190028D02*
X1062276D01*
G01X1032276Y189528D02*
X1062276D01*
G01X1017226Y188478D02*
X1019926D01*
G01X1024376Y187528D02*
X1007876D01*
G01X1062276Y182028D02*
X1032276D01*
G01X1019926Y178578D02*
X1017226D01*
G01X1050305Y227028D02*
G03X1046846I-1730J-1020D01*
G01X1046823Y215028D02*
G03X1050328I1752J980D01*
G01X1046823Y235028D02*
G03X1050328I1752J980D01*
G01X1046846Y227028D02*
G03X1050305I1730J-1020D01*
G01X1050328Y215028D02*
G03X1046823I-1753J980D01*
G01X1050328Y235028D02*
G03X1046823I-1753J980D01*
G01X1040305Y227028D02*
G03X1036846I-1730J-1020D01*
G01X1036823Y215028D02*
G03X1040328I1752J980D01*
G01X1036823Y235028D02*
G03X1040328I1752J980D01*
G01X1036846Y227028D02*
G03X1040305I1730J-1020D01*
G01X1040328Y215028D02*
G03X1036823I-1753J980D01*
G01X1040328Y235028D02*
G03X1036823I-1753J980D01*
G01X1030305Y227028D02*
G03X1026846I-1729J-1020D01*
G01X1026823Y215028D02*
G03X1030328I1753J980D01*
G01X1026823Y235028D02*
G03X1030328I1753J980D01*
G01X1026846Y227028D02*
G03X1030305I1730J-1020D01*
G01X1030328Y215028D02*
G03X1026823I-1753J980D01*
G01X1030328Y235028D02*
G03X1026823I-1753J980D01*
G01X1050305Y207028D02*
G03X1046846I-1730J-1020D01*
G01X1040305D02*
G03X1036846I-1730J-1020D01*
G01X1030305D02*
G03X1026846I-1729J-1020D01*
G01X1046846D02*
G03X1050305I1730J-1020D01*
G01X1036846D02*
G03X1040305I1730J-1020D01*
G01X1026846D02*
G03X1030305I1730J-1020D01*
G01X1020305D02*
G03X1016846I-1730J-1020D01*
G01X1020305Y227028D02*
G03X1016846I-1730J-1020D01*
G01X1016823Y215028D02*
G03X1020328I1752J980D01*
G01X1016823Y235028D02*
G03X1020328I1752J980D01*
G01X1016846Y207028D02*
G03X1020305I1729J-1020D01*
G01X1016846Y227028D02*
G03X1020305I1729J-1020D01*
G01X1020328Y215028D02*
G03X1016823I-1753J980D01*
G01X1020328Y235028D02*
G03X1016823I-1753J980D01*
G01X1057076Y243528D02*
Y293528D01*
G01X1051206Y215028D02*
Y207028D01*
G01Y235028D02*
Y227028D01*
G01X1049826Y235028D02*
Y237028D01*
G01Y225028D02*
Y227028D01*
G01Y215028D02*
Y217028D01*
G01Y205028D02*
Y207028D01*
G01X1047326D02*
Y205028D01*
G01Y217028D02*
Y215028D01*
G01Y227028D02*
Y225028D01*
G01Y237028D02*
Y235028D01*
G01X1047281Y207028D02*
Y205028D01*
G01Y217028D02*
Y215028D01*
G01Y227028D02*
Y225028D01*
G01Y237028D02*
Y235028D01*
G01X1042488Y207028D02*
Y205028D01*
G01Y217028D02*
Y215028D01*
G01Y227028D02*
Y225028D01*
G01Y237028D02*
Y235028D01*
G01X1039826D02*
Y237028D01*
G01Y225028D02*
Y227028D01*
G01Y215028D02*
Y217028D01*
G01Y205028D02*
Y207028D01*
G01X1037326D02*
Y205028D01*
G01Y217028D02*
Y215028D01*
G01Y227028D02*
Y225028D01*
G01Y237028D02*
Y235028D01*
G01X1029826D02*
Y237028D01*
G01Y225028D02*
Y227028D01*
G01Y215028D02*
Y217028D01*
G01Y205028D02*
Y207028D01*
G01X1027326D02*
Y205028D01*
G01Y217028D02*
Y215028D01*
G01Y227028D02*
Y225028D01*
G01Y237028D02*
Y235028D01*
G01X1021213Y207028D02*
Y205028D01*
G01Y217028D02*
Y215028D01*
G01Y227028D02*
Y225028D01*
G01Y237028D02*
Y235028D01*
G01X1019826D02*
Y237028D01*
G01Y225028D02*
Y227028D01*
G01Y215028D02*
Y217028D01*
G01Y205028D02*
Y207028D01*
G01X1017326D02*
Y205028D01*
G01Y217028D02*
Y215028D01*
G01Y227028D02*
Y225028D01*
G01Y237028D02*
Y235028D01*
G01X1016420D02*
Y237028D01*
G01Y225028D02*
Y227028D01*
G01Y215028D02*
Y217028D01*
G01Y205028D02*
Y207028D01*
G01X1015806Y227028D02*
Y235028D01*
G01Y207028D02*
Y215028D01*
G01X1010076Y243528D02*
Y293528D01*
G01X1009876Y198528D02*
Y243528D01*
G01X1057076D02*
X1059271D01*
G01X1007880D02*
X1010076D01*
G01X1016420Y237028D02*
X1047281D01*
G01X1049826D02*
X1047326D01*
G01X1015806Y235028D02*
X1051206D01*
G01X1015806Y227028D02*
X1051206D01*
G01X1047326Y225028D02*
X1049826D01*
G01X1016420D02*
X1047281D01*
G01X1016420Y217028D02*
X1047281D01*
G01X1049826D02*
X1047326D01*
G01X1015806Y215028D02*
X1051206D01*
G01X1015806Y207028D02*
X1051206D01*
G01X1047326Y205028D02*
X1049826D01*
G01X1016420D02*
X1047281D01*
G01X1007876Y198528D02*
X1059276D01*
G01Y194528D02*
X1024376D01*
G01X1050583Y278528D02*
G03I-2007J0D01*
G01Y288528D02*
G03I-2007J0D01*
G01X1040583Y278528D02*
G03I-2007J0D01*
G01Y288528D02*
G03I-2007J0D01*
G01X1050583Y248528D02*
G03I-2007J0D01*
G01Y258528D02*
G03I-2007J0D01*
G01Y268528D02*
G03I-2007J0D01*
G01X1040583Y248528D02*
G03I-2007J0D01*
G01Y258528D02*
G03I-2007J0D01*
G01Y268528D02*
G03I-2007J0D01*
G01X1030583Y278528D02*
G03I-2007J0D01*
G01Y288528D02*
G03I-2007J0D01*
G01Y248528D02*
G03I-2007J0D01*
G01Y258528D02*
G03I-2007J0D01*
G01Y268528D02*
G03I-2007J0D01*
G01X1020583Y248528D02*
G03I-2007J0D01*
G01Y258528D02*
G03I-2007J0D01*
G01Y268528D02*
G03I-2007J0D01*
G01Y278528D02*
G03I-2007J0D01*
G01Y288528D02*
G03I-2007J0D01*
G01X1049826Y249778D02*
X1050216Y250169D01*
G01X1047326Y247278D02*
X1046935Y246888D01*
G01X1049826Y259778D02*
X1050216Y260169D01*
G01X1036935Y246888D02*
X1037326Y247278D01*
G01X1040216Y250169D02*
X1039826Y249778D01*
G01X1047326Y257278D02*
X1046935Y256888D01*
G01X1049826Y269778D02*
X1050216Y270169D01*
G01X1036935Y256888D02*
X1037326Y257278D01*
G01X1026935Y246888D02*
X1027326Y247278D01*
G01X1030216Y250169D02*
X1029826Y249778D01*
G01X1040216Y260169D02*
X1039826Y259778D01*
G01X1047326Y267278D02*
X1046935Y266888D01*
G01X1049826Y279778D02*
X1050216Y280169D01*
G01X1036935Y266888D02*
X1037326Y267278D01*
G01X1026935Y256888D02*
X1027326Y257278D01*
G01X1016935Y246888D02*
X1017326Y247278D01*
G01X1020216Y250169D02*
X1019826Y249778D01*
G01X1030216Y260169D02*
X1029826Y259778D01*
G01X1040216Y270169D02*
X1039826Y269778D01*
G01X1047326Y277278D02*
X1046935Y276888D01*
G01X1049826Y289778D02*
X1050216Y290169D01*
G01X1036935Y276888D02*
X1037326Y277278D01*
G01X1026935Y266888D02*
X1027326Y267278D01*
G01X1016935Y256888D02*
X1017326Y257278D01*
G01X1020216Y260169D02*
X1019826Y259778D01*
G01X1030216Y270169D02*
X1029826Y269778D01*
G01X1040216Y280169D02*
X1039826Y279778D01*
G01X1047326Y287278D02*
X1046935Y286888D01*
G01X1036935D02*
X1037326Y287278D01*
G01X1026935Y276888D02*
X1027326Y277278D01*
G01X1016935Y266888D02*
X1017326Y267278D01*
G01X1020216Y270169D02*
X1019826Y269778D01*
G01X1030216Y280169D02*
X1029826Y279778D01*
G01X1040216Y290169D02*
X1039826Y289778D01*
G01X1026935Y286888D02*
X1027326Y287278D01*
G01X1016935Y276888D02*
X1017326Y277278D01*
G01X1020216Y280169D02*
X1019826Y279778D01*
G01X1030216Y290169D02*
X1029826Y289778D01*
G01X1016935Y286888D02*
X1017326Y287278D01*
G01X1020216Y290169D02*
X1019826Y289778D01*
G01X1050216Y286888D02*
Y290169D01*
G01Y276888D02*
Y280169D01*
G01Y266888D02*
Y270169D01*
G01Y256888D02*
Y260169D01*
G01Y246888D02*
Y250169D01*
G01X1049956Y249908D02*
Y247148D01*
G01Y259908D02*
Y257148D01*
G01Y269908D02*
Y267148D01*
G01Y279908D02*
Y277148D01*
G01Y289908D02*
Y287148D01*
G01X1049826Y249778D02*
Y247278D01*
G01Y259778D02*
Y257278D01*
G01Y269778D02*
Y267278D01*
G01Y279778D02*
Y277278D01*
G01Y289778D02*
Y287278D01*
G01X1047326Y249778D02*
Y247278D01*
G01Y259778D02*
Y257278D01*
G01Y269778D02*
Y267278D01*
G01Y279778D02*
Y277278D01*
G01Y289778D02*
Y287278D01*
G01X1047196Y249908D02*
Y247148D01*
G01Y259908D02*
Y257148D01*
G01Y269908D02*
Y267148D01*
G01Y279908D02*
Y277148D01*
G01Y289908D02*
Y287148D01*
G01X1046935Y250169D02*
Y246888D01*
G01Y260169D02*
Y256888D01*
G01Y270169D02*
Y266888D01*
G01Y280169D02*
Y276888D01*
G01Y290169D02*
Y286888D01*
G01X1040216Y250169D02*
Y246888D01*
G01Y260169D02*
Y256888D01*
G01Y270169D02*
Y266888D01*
G01Y280169D02*
Y276888D01*
G01Y290169D02*
Y286888D01*
G01X1039956Y249908D02*
Y247148D01*
G01Y259908D02*
Y257148D01*
G01Y269908D02*
Y267148D01*
G01Y279908D02*
Y277148D01*
G01Y289908D02*
Y287148D01*
G01X1039826Y249778D02*
Y247278D01*
G01Y259778D02*
Y257278D01*
G01Y269778D02*
Y267278D01*
G01Y279778D02*
Y277278D01*
G01Y289778D02*
Y287278D01*
G01X1037326D02*
Y289778D01*
G01Y277278D02*
Y279778D01*
G01Y267278D02*
Y269778D01*
G01Y257278D02*
Y259778D01*
G01Y247278D02*
Y249778D01*
G01X1037196Y287148D02*
Y289908D01*
G01Y277148D02*
Y279908D01*
G01Y267148D02*
Y269908D01*
G01Y257148D02*
Y259908D01*
G01Y247148D02*
Y249908D01*
G01X1036935Y286888D02*
Y290169D01*
G01Y276888D02*
Y280169D01*
G01Y266888D02*
Y270169D01*
G01Y256888D02*
Y260169D01*
G01Y246888D02*
Y250169D01*
G01X1030216D02*
Y246888D01*
G01Y260169D02*
Y256888D01*
G01Y270169D02*
Y266888D01*
G01Y280169D02*
Y276888D01*
G01Y290169D02*
Y286888D01*
G01X1029956Y249908D02*
Y247148D01*
G01Y259908D02*
Y257148D01*
G01Y269908D02*
Y267148D01*
G01Y279908D02*
Y277148D01*
G01Y289908D02*
Y287148D01*
G01X1029826Y249778D02*
Y247278D01*
G01Y259778D02*
Y257278D01*
G01Y269778D02*
Y267278D01*
G01Y279778D02*
Y277278D01*
G01Y289778D02*
Y287278D01*
G01X1027326D02*
Y289778D01*
G01Y277278D02*
Y279778D01*
G01Y267278D02*
Y269778D01*
G01Y257278D02*
Y259778D01*
G01Y247278D02*
Y249778D01*
G01X1027196Y287148D02*
Y289908D01*
G01Y277148D02*
Y279908D01*
G01Y267148D02*
Y269908D01*
G01Y257148D02*
Y259908D01*
G01Y247148D02*
Y249908D01*
G01X1026935Y286888D02*
Y290169D01*
G01Y276888D02*
Y280169D01*
G01Y266888D02*
Y270169D01*
G01Y256888D02*
Y260169D01*
G01Y246888D02*
Y250169D01*
G01X1020216D02*
Y246888D01*
G01Y260169D02*
Y256888D01*
G01Y270169D02*
Y266888D01*
G01Y280169D02*
Y276888D01*
G01Y290169D02*
Y286888D01*
G01X1019956Y249908D02*
Y247148D01*
G01Y259908D02*
Y257148D01*
G01Y269908D02*
Y267148D01*
G01Y279908D02*
Y277148D01*
G01Y289908D02*
Y287148D01*
G01X1019826Y249778D02*
Y247278D01*
G01Y259778D02*
Y257278D01*
G01Y269778D02*
Y267278D01*
G01Y279778D02*
Y277278D01*
G01Y289778D02*
Y287278D01*
G01X1017326D02*
Y289778D01*
G01Y277278D02*
Y279778D01*
G01Y267278D02*
Y269778D01*
G01Y257278D02*
Y259778D01*
G01Y247278D02*
Y249778D01*
G01X1017196Y287148D02*
Y289908D01*
G01Y277148D02*
Y279908D01*
G01Y267148D02*
Y269908D01*
G01Y257148D02*
Y259908D01*
G01Y247148D02*
Y249908D01*
G01X1016935Y286888D02*
Y290169D01*
G01Y276888D02*
Y280169D01*
G01Y266888D02*
Y270169D01*
G01Y256888D02*
Y260169D01*
G01Y246888D02*
Y250169D01*
G01X1009876Y293528D02*
Y338528D01*
G01X1049826Y287278D02*
X1050216Y286888D01*
G01X1046935Y290169D02*
X1047326Y289778D01*
G01X1049826Y277278D02*
X1050216Y276888D01*
G01X1046935Y280169D02*
X1047326Y279778D01*
G01X1039826Y287278D02*
X1040216Y286888D01*
G01X1036935Y290169D02*
X1037326Y289778D01*
G01X1049826Y267278D02*
X1050216Y266888D01*
G01X1046935Y270169D02*
X1047326Y269778D01*
G01X1039826Y277278D02*
X1040216Y276888D01*
G01X1036935Y280169D02*
X1037326Y279778D01*
G01X1029826Y287278D02*
X1030216Y286888D01*
G01X1026935Y290169D02*
X1027326Y289778D01*
G01X1049826Y257278D02*
X1050216Y256888D01*
G01X1046935Y260169D02*
X1047326Y259778D01*
G01X1039826Y267278D02*
X1040216Y266888D01*
G01X1036935Y270169D02*
X1037326Y269778D01*
G01X1029826Y277278D02*
X1030216Y276888D01*
G01X1026935Y280169D02*
X1027326Y279778D01*
G01X1019826Y287278D02*
X1020216Y286888D01*
G01X1016935Y290169D02*
X1017326Y289778D01*
G01X1049826Y247278D02*
X1050216Y246888D01*
G01X1046935Y250169D02*
X1047326Y249778D01*
G01X1039826Y257278D02*
X1040216Y256888D01*
G01X1036935Y260169D02*
X1037326Y259778D01*
G01X1029826Y267278D02*
X1030216Y266888D01*
G01X1026935Y270169D02*
X1027326Y269778D01*
G01X1019826Y277278D02*
X1020216Y276888D01*
G01X1016935Y280169D02*
X1017326Y279778D01*
G01X1039826Y247278D02*
X1040216Y246888D01*
G01X1036935Y250169D02*
X1037326Y249778D01*
G01X1029826Y257278D02*
X1030216Y256888D01*
G01X1026935Y260169D02*
X1027326Y259778D01*
G01X1019826Y267278D02*
X1020216Y266888D01*
G01X1016935Y270169D02*
X1017326Y269778D01*
G01X1029826Y247278D02*
X1030216Y246888D01*
G01X1026935Y250169D02*
X1027326Y249778D01*
G01X1019826Y257278D02*
X1020216Y256888D01*
G01X1016935Y260169D02*
X1017326Y259778D01*
G01X1019826Y247278D02*
X1020216Y246888D01*
G01X1016935Y250169D02*
X1017326Y249778D01*
G01X1057076Y293528D02*
X1059271D01*
G01X1007880D02*
X1010076D01*
G01X1036935Y290169D02*
X1040216D01*
G01X1026935D02*
X1030216D01*
G01X1016935D02*
X1020216D01*
G01X1050216D02*
X1046935D01*
G01X1047196Y289908D02*
X1049956D01*
G01X1037196D02*
X1039956D01*
G01X1027196D02*
X1029956D01*
G01X1017196D02*
X1019956D01*
G01X1047326Y289778D02*
X1049826D01*
G01X1037326D02*
X1039826D01*
G01X1027326D02*
X1029826D01*
G01X1017326D02*
X1019826D01*
G01Y287278D02*
X1017326D01*
G01X1029826D02*
X1027326D01*
G01X1039826D02*
X1037326D01*
G01X1049826D02*
X1047326D01*
G01X1019956Y287148D02*
X1017196D01*
G01X1029956D02*
X1027196D01*
G01X1039956D02*
X1037196D01*
G01X1049956D02*
X1047196D01*
G01X1046935Y286888D02*
X1050216D01*
G01X1020216D02*
X1016935D01*
G01X1030216D02*
X1026935D01*
G01X1040216D02*
X1036935D01*
G01Y280169D02*
X1040216D01*
G01X1026935D02*
X1030216D01*
G01X1016935D02*
X1020216D01*
G01X1050216D02*
X1046935D01*
G01X1047196Y279908D02*
X1049956D01*
G01X1037196D02*
X1039956D01*
G01X1027196D02*
X1029956D01*
G01X1017196D02*
X1019956D01*
G01X1047326Y279778D02*
X1049826D01*
G01X1037326D02*
X1039826D01*
G01X1027326D02*
X1029826D01*
G01X1017326D02*
X1019826D01*
G01Y277278D02*
X1017326D01*
G01X1029826D02*
X1027326D01*
G01X1039826D02*
X1037326D01*
G01X1049826D02*
X1047326D01*
G01X1019956Y277148D02*
X1017196D01*
G01X1029956D02*
X1027196D01*
G01X1039956D02*
X1037196D01*
G01X1049956D02*
X1047196D01*
G01X1046935Y276888D02*
X1050216D01*
G01X1020216D02*
X1016935D01*
G01X1030216D02*
X1026935D01*
G01X1040216D02*
X1036935D01*
G01Y270169D02*
X1040216D01*
G01X1026935D02*
X1030216D01*
G01X1016935D02*
X1020216D01*
G01X1050216D02*
X1046935D01*
G01X1047196Y269908D02*
X1049956D01*
G01X1037196D02*
X1039956D01*
G01X1027196D02*
X1029956D01*
G01X1017196D02*
X1019956D01*
G01X1047326Y269778D02*
X1049826D01*
G01X1037326D02*
X1039826D01*
G01X1027326D02*
X1029826D01*
G01X1017326D02*
X1019826D01*
G01Y267278D02*
X1017326D01*
G01X1029826D02*
X1027326D01*
G01X1039826D02*
X1037326D01*
G01X1049826D02*
X1047326D01*
G01X1019956Y267148D02*
X1017196D01*
G01X1029956D02*
X1027196D01*
G01X1039956D02*
X1037196D01*
G01X1049956D02*
X1047196D01*
G01X1046935Y266888D02*
X1050216D01*
G01X1020216D02*
X1016935D01*
G01X1030216D02*
X1026935D01*
G01X1040216D02*
X1036935D01*
G01Y260169D02*
X1040216D01*
G01X1026935D02*
X1030216D01*
G01X1016935D02*
X1020216D01*
G01X1050216D02*
X1046935D01*
G01X1047196Y259908D02*
X1049956D01*
G01X1037196D02*
X1039956D01*
G01X1027196D02*
X1029956D01*
G01X1017196D02*
X1019956D01*
G01X1047326Y259778D02*
X1049826D01*
G01X1037326D02*
X1039826D01*
G01X1027326D02*
X1029826D01*
G01X1017326D02*
X1019826D01*
G01Y257278D02*
X1017326D01*
G01X1029826D02*
X1027326D01*
G01X1039826D02*
X1037326D01*
G01X1049826D02*
X1047326D01*
G01X1019956Y257148D02*
X1017196D01*
G01X1029956D02*
X1027196D01*
G01X1039956D02*
X1037196D01*
G01X1049956D02*
X1047196D01*
G01X1046935Y256888D02*
X1050216D01*
G01X1020216D02*
X1016935D01*
G01X1030216D02*
X1026935D01*
G01X1040216D02*
X1036935D01*
G01Y250169D02*
X1040216D01*
G01X1026935D02*
X1030216D01*
G01X1016935D02*
X1020216D01*
G01X1050216D02*
X1046935D01*
G01X1047196Y249908D02*
X1049956D01*
G01X1037196D02*
X1039956D01*
G01X1027196D02*
X1029956D01*
G01X1017196D02*
X1019956D01*
G01X1047326Y249778D02*
X1049826D01*
G01X1037326D02*
X1039826D01*
G01X1027326D02*
X1029826D01*
G01X1017326D02*
X1019826D01*
G01Y247278D02*
X1017326D01*
G01X1029826D02*
X1027326D01*
G01X1039826D02*
X1037326D01*
G01X1049826D02*
X1047326D01*
G01X1019956Y247148D02*
X1017196D01*
G01X1029956D02*
X1027196D01*
G01X1039956D02*
X1037196D01*
G01X1049956D02*
X1047196D01*
G01X1046935Y246888D02*
X1050216D01*
G01X1020216D02*
X1016935D01*
G01X1030216D02*
X1026935D01*
G01X1040216D02*
X1036935D01*
G01X1050328Y322029D02*
G03X1046823I-1753J-981D01*
G01X1046846Y310028D02*
G03X1050305I1730J1020D01*
G01X1046846Y330028D02*
G03X1050305I1730J1020D01*
G01X1046823Y322029D02*
G03X1050328I1752J-981D01*
G01X1050305Y310028D02*
G03X1046846I-1730J1020D01*
G01X1050305Y330028D02*
G03X1046846I-1730J1020D01*
G01X1050328Y302029D02*
G03X1046823I-1753J-981D01*
G01D02*
G03X1050328I1752J-981D01*
G01X1040328Y322029D02*
G03X1036823I-1753J-981D01*
G01X1036846Y310028D02*
G03X1040305I1730J1020D01*
G01X1036846Y330028D02*
G03X1040305I1730J1020D01*
G01X1036823Y322029D02*
G03X1040328I1752J-981D01*
G01X1040305Y310028D02*
G03X1036846I-1730J1020D01*
G01X1040305Y330028D02*
G03X1036846I-1730J1020D01*
G01X1040328Y302029D02*
G03X1036823I-1753J-981D01*
G01D02*
G03X1040328I1752J-981D01*
G01X1030328D02*
G03X1026823I-1753J-981D01*
G01X1030328Y322029D02*
G03X1026823I-1753J-981D01*
G01X1026846Y310028D02*
G03X1030305I1730J1020D01*
G01X1026846Y330028D02*
G03X1030305I1730J1020D01*
G01X1026823Y302029D02*
G03X1030328I1753J-981D01*
G01X1026823Y322029D02*
G03X1030328I1753J-981D01*
G01X1030305Y310028D02*
G03X1026846I-1729J1020D01*
G01X1030305Y330028D02*
G03X1026846I-1729J1020D01*
G01X1020328Y302029D02*
G03X1016823I-1753J-981D01*
G01X1020328Y322029D02*
G03X1016823I-1753J-981D01*
G01X1016846Y310028D02*
G03X1020305I1729J1020D01*
G01X1016846Y330028D02*
G03X1020305I1729J1020D01*
G01X1016823Y302029D02*
G03X1020328I1752J-981D01*
G01X1016823Y322029D02*
G03X1020328I1752J-981D01*
G01X1020305Y310028D02*
G03X1016846I-1730J1020D01*
G01X1020305Y330028D02*
G03X1016846I-1730J1020D01*
G01X1021713Y330875D02*
X1021638Y330850D01*
G01Y330998D02*
X1021713Y331022D01*
G01X1021814Y330949D02*
X1021713Y330875D01*
G01Y331022D02*
X1021763Y331072D01*
G01X1021889Y331047D02*
X1021814Y330949D01*
G01X1021763Y331072D02*
X1021789Y331145D01*
G01X1021914Y331170D02*
X1021889Y331047D01*
G01X1051206Y310028D02*
Y302028D01*
G01Y330028D02*
Y322028D01*
G01X1049826Y330028D02*
Y332028D01*
G01Y320028D02*
Y322028D01*
G01Y310028D02*
Y312028D01*
G01Y300028D02*
Y302028D01*
G01X1047326D02*
Y300028D01*
G01Y312028D02*
Y310028D01*
G01Y322028D02*
Y320028D01*
G01Y332028D02*
Y330028D01*
G01X1047281Y302028D02*
Y300028D01*
G01Y312028D02*
Y310028D01*
G01Y322028D02*
Y320028D01*
G01Y332028D02*
Y330028D01*
G01X1042488Y302028D02*
Y300028D01*
G01Y312028D02*
Y310028D01*
G01Y322028D02*
Y320028D01*
G01Y332028D02*
Y330028D01*
G01X1039826D02*
Y332028D01*
G01Y320028D02*
Y322028D01*
G01Y310028D02*
Y312028D01*
G01Y300028D02*
Y302028D01*
G01X1037326D02*
Y300028D01*
G01Y312028D02*
Y310028D01*
G01Y322028D02*
Y320028D01*
G01Y332028D02*
Y330028D01*
G01X1032276Y347528D02*
Y383528D01*
G01Y347028D02*
Y347528D01*
G01X1029826Y330028D02*
Y332028D01*
G01Y320028D02*
Y322028D01*
G01Y310028D02*
Y312028D01*
G01Y300028D02*
Y302028D01*
G01X1027326D02*
Y300028D01*
G01Y312028D02*
Y310028D01*
G01Y322028D02*
Y320028D01*
G01Y332028D02*
Y330028D01*
G01X1024376Y349528D02*
Y342528D01*
G01X1021914Y330506D02*
Y330358D01*
G01Y331761D02*
Y331170D01*
G01X1021789Y331145D02*
Y331613D01*
G01X1021412D02*
Y331145D01*
G01X1021261Y331170D02*
Y331613D01*
G01X1021213Y302028D02*
Y300028D01*
G01Y312028D02*
Y310028D01*
G01Y322028D02*
Y320028D01*
G01Y332028D02*
Y330028D01*
G01X1020733Y331613D02*
Y331761D01*
G01Y330358D02*
Y330506D01*
G01X1019826Y330028D02*
Y332028D01*
G01Y320028D02*
Y322028D01*
G01Y310028D02*
Y312028D01*
G01Y300028D02*
Y302028D01*
G01X1017326D02*
Y300028D01*
G01Y312028D02*
Y310028D01*
G01Y322028D02*
Y320028D01*
G01Y332028D02*
Y330028D01*
G01X1016420D02*
Y332028D01*
G01Y320028D02*
Y322028D01*
G01Y310028D02*
Y312028D01*
G01Y300028D02*
Y302028D01*
G01X1015806Y322028D02*
Y330028D01*
G01Y302028D02*
Y310028D01*
G01X1021286Y331047D02*
X1021261Y331170D01*
G01X1021412Y331145D02*
X1021437Y331072D01*
G01X1021361Y330949D02*
X1021286Y331047D01*
G01X1021437Y331072D02*
X1021487Y331022D01*
G01X1021738Y330653D02*
X1021914Y330506D01*
G01X1021713D02*
X1021537Y330653D01*
G01X1021462Y330875D02*
X1021361Y330949D01*
G01X1021487Y331022D02*
X1021562Y330998D01*
G01X1021537Y330850D02*
X1021462Y330875D01*
G01X1062276Y347528D02*
X1032276D01*
G01X1062276Y347028D02*
X1032276D01*
G01X1024376Y342528D02*
X1059276D01*
G01X1007876Y338528D02*
X1059276D01*
G01X1016420Y332028D02*
X1047281D01*
G01X1049826D02*
X1047326D01*
G01X1020733Y331761D02*
X1021914D01*
G01X1021261Y331613D02*
X1020733D01*
G01X1021789D02*
X1021412D01*
G01X1021562Y330998D02*
X1021638D01*
G01Y330850D02*
X1021537D01*
G01Y330653D02*
X1021738D01*
G01X1020733Y330506D02*
X1021713D01*
G01X1021914Y330358D02*
X1020733D01*
G01X1015806Y330028D02*
X1051206D01*
G01X1015806Y322028D02*
X1051206D01*
G01X1047326Y320028D02*
X1049826D01*
G01X1016420D02*
X1047281D01*
G01X1016420Y312028D02*
X1047281D01*
G01X1049826D02*
X1047326D01*
G01X1015806Y310028D02*
X1051206D01*
G01X1015806Y302028D02*
X1051206D01*
G01X1047326Y300028D02*
X1049826D01*
G01X1016420D02*
X1047281D01*
G01X1023477Y353528D02*
G03I-4901J0D01*
G01X1024676Y373528D02*
G03I-6100J0D01*
G01X1024835D02*
G03I-6259J0D01*
G01X1019926Y358478D02*
Y348578D01*
G01X1017226D02*
Y358478D01*
G01D02*
X1019926D01*
G01X1032276Y355028D02*
X1062276D01*
G01X1007876Y349528D02*
X1024376D01*
G01X1019926Y348578D02*
X1017226D01*
G01X1063851Y614985D02*
G03I-15748J0D01*
G01X1054993D02*
G03I-6890J0D01*
G01X1016607Y954552D02*
Y949631D01*
G01Y982439D02*
Y977518D01*
G01Y1046415D02*
X1015769Y1050517D01*
G01X1012419Y1047236D02*
X1011581Y1049696D01*
G01X1015769Y1050517D02*
X1013256Y1054618D01*
G01X1011581Y1049696D02*
X1009906Y1052157D01*
G01X1013256Y1054618D02*
X1009906Y1057078D01*
G01Y1052157D02*
X1007393Y1053797D01*
G01Y1034933D02*
X1009906Y1036573D01*
G01Y1031652D02*
X1013256Y1034112D01*
G01X1009906Y1036573D02*
X1011581Y1039034D01*
G01X1013256Y1034112D02*
X1015769Y1038213D01*
G01X1011581Y1039034D02*
X1012419Y1041494D01*
G01X1015769Y1038213D02*
X1016607Y1042314D01*
G01D02*
Y1046415D01*
G01Y1022629D02*
Y1017708D01*
G01X1012419Y1041494D02*
Y1047236D01*
G01X1016607Y1069381D02*
Y1065280D01*
G01Y1082505D02*
Y1078404D01*
G01Y1095628D02*
Y1091527D01*
G01Y1106291D02*
Y1102190D01*
G01Y1119414D02*
Y1115313D01*
G01Y1132538D02*
Y1128436D01*
G01X1054993Y1205536D02*
G03I-6890J0D01*
G01X1063851D02*
G03I-15748J0D01*
G01X1021332Y1339985D02*
Y1318922D01*
G01X1055780Y1372859D02*
G03I-7874J0D01*
G01X1056371D02*
G03I-8465J0D01*
G01X1056765D02*
G03I-8859J0D01*
G01X1057355D02*
G03I-9449J0D01*
G01X1057749D02*
G03I-9843J0D01*
G01X1063064D02*
G03I-15158J0D01*
G01X1063654D02*
G03I-15748J0D01*
G01X1066607D02*
G03I-18701J0D01*
G01X1042395Y1339985D02*
G03Y1405733I0J32874D01*
G01Y1339985D02*
X1021332D01*
G01Y1405733D02*
X1042395D01*
G01X1021332Y1426796D02*
Y1405733D01*
G01X1049087Y1791953D02*
G03I-18701J0D01*
G01X1045543D02*
G03I-15157J0D01*
G01X1046134D02*
G03I-15748J0D01*
G01X1007748Y1816244D02*
G03Y1829630I0J6693D01*
G01Y1816244D02*
G03Y1829630I0J6693D01*
G01X1016843Y1814000D02*
Y1831874D01*
G01X1038260Y1791953D02*
G03I-7874J0D01*
G01X1038850D02*
G03I-8464J0D01*
G01X1039244D02*
G03I-8858J0D01*
G01X1039835D02*
G03I-9449J0D01*
G01X1040130D02*
G03I-9744J0D01*
G01X1040228D02*
G03I-9842J0D01*
G01D02*
G03I-9842J0D01*
G01X1009166Y1821678D02*
Y1824198D01*
G01D02*
X1006647D01*
G01Y1821678D02*
X1009166D01*
G01X1006647Y1824198D02*
Y1821678D01*
G01X1011997Y1817938D02*
X1012907Y1819513D01*
G01D02*
Y1826363D01*
G01X1011289Y1822626D02*
X1011562Y1822514D01*
G01X1010523Y1821285D02*
X1010304Y1821340D01*
G01X1011125Y1823575D02*
X1010851Y1823631D01*
G01X1010304Y1821620D02*
X1010578Y1821564D01*
G01X1011179Y1822458D02*
X1010851Y1822514D01*
G01X1010796Y1823911D02*
X1011179Y1823855D01*
G01X1010687Y1823911D02*
X1010796D01*
G01X1010851Y1823631D02*
X1010632D01*
G01X1010085Y1823296D02*
X1009812D01*
G01X1010632Y1822737D02*
X1010851D01*
G01Y1822514D02*
X1010632D01*
G01X1009757Y1821899D02*
X1010031D01*
G01X1010578Y1821564D02*
X1010906D01*
G01X1010961Y1821285D02*
X1010523D01*
G01X1010304Y1823855D02*
X1010687Y1823911D01*
G01X1010632Y1823631D02*
X1010359Y1823575D01*
G01X1010906Y1821564D02*
X1011179Y1821620D01*
G01Y1821340D02*
X1010961Y1821285D01*
G01X1011289Y1823464D02*
X1011125Y1823575D01*
G01X1011344Y1822346D02*
X1011179Y1822458D01*
G01X1010085Y1821452D02*
X1009921Y1821564D01*
G01X1011179Y1823855D02*
X1011398Y1823743D01*
G01X1010195Y1821676D02*
X1010304Y1821620D01*
G01Y1821340D02*
X1010085Y1821452D01*
G01X1011398Y1823743D02*
X1011617Y1823520D01*
G01X1010085Y1821787D02*
X1010195Y1821676D01*
G01X1011398Y1823296D02*
X1011289Y1823464D01*
G01X1011562Y1822514D02*
X1011672Y1822346D01*
G01X1009921Y1821564D02*
X1009812Y1821732D01*
G01X1011453Y1822123D02*
X1011344Y1822346D01*
G01X1010031Y1821899D02*
X1010085Y1821787D01*
G01X1009812Y1821732D02*
X1009757Y1821899D01*
G01X1011617Y1823520D02*
X1011672Y1823296D01*
G01Y1822346D02*
X1011726Y1822123D01*
G01D02*
Y1821899D01*
G01X1011672Y1823296D02*
Y1823184D01*
G01X1011453Y1821899D02*
Y1822123D01*
G01X1011398Y1823184D02*
Y1823296D01*
G01X1010632Y1822514D02*
Y1822737D01*
G01X1011672Y1823184D02*
X1011617Y1822961D01*
G01X1009812Y1823296D02*
X1009866Y1823520D01*
G01X1011726Y1821899D02*
X1011672Y1821732D01*
G01X1011398Y1821787D02*
X1011453Y1821899D01*
G01X1011289Y1822961D02*
X1011398Y1823184D01*
G01X1011672Y1821732D02*
X1011562Y1821564D01*
G01X1011617Y1822961D02*
X1011508Y1822793D01*
G01X1010195Y1823464D02*
X1010085Y1823296D01*
G01X1011289Y1821676D02*
X1011398Y1821787D01*
G01X1011179Y1822849D02*
X1011289Y1822961D01*
G01X1009866Y1823520D02*
X1010085Y1823743D01*
G01X1011562Y1821564D02*
X1011398Y1821452D01*
G01X1010359Y1823575D02*
X1010195Y1823464D01*
G01X1011508Y1822793D02*
X1011289Y1822626D01*
G01X1011398Y1821452D02*
X1011179Y1821340D01*
G01Y1821620D02*
X1011289Y1821676D01*
G01X1010085Y1823743D02*
X1010304Y1823855D01*
G01X1010851Y1822737D02*
X1011179Y1822849D01*
G01X1012907Y1826363D02*
X1011997Y1827938D01*
G01X1049087Y1867150D02*
G03I-18701J0D01*
G01X1038260D02*
G03I-7874J0D01*
G01X1038850D02*
G03I-8464J0D01*
G01X1039244D02*
G03I-8858J0D01*
G01X1039835D02*
G03I-9449J0D01*
G01X1040130D02*
G03I-9744J0D01*
G01X1040228D02*
G03I-9842J0D01*
G01D02*
G03I-9842J0D01*
G01X1045543D02*
G03I-15157J0D01*
G01X1046134D02*
G03I-15748J0D01*
G01X1055977Y1933883D02*
G03I-7874J0D01*
G01X1063851D02*
G03I-15748J0D01*
G01X1010110Y2112671D02*
Y2093734D01*
G01X1072198Y-37358D02*
X1072920Y-36708D01*
X1073353Y-35950D01*
X1073497Y-34976D01*
X1073208Y-34002D01*
X1072631Y-33244D01*
X1071621Y-32702D01*
X1070466Y-32594D01*
X1069311Y-32811D01*
X1068589Y-33352D01*
X1068012Y-34110D01*
X1067867Y-34868D01*
X1068012Y-35626D01*
X1068589Y-36600D01*
X1064836Y-36275D01*
Y-33352D01*
G01X1066279Y-28372D02*
X1065414Y-27722D01*
X1064980Y-26965D01*
X1064836Y-26098D01*
X1065125Y-25016D01*
X1065846Y-24258D01*
X1066712Y-24041D01*
X1067579Y-24150D01*
X1068300Y-24583D01*
X1069744Y-26748D01*
X1070754Y-27722D01*
X1072198Y-28372D01*
X1073497Y-28589D01*
Y-24041D01*
G01X1073786Y-17654D02*
X1073641Y-17871D01*
X1073353D01*
X1073208Y-17654D01*
X1073353Y-17437D01*
X1073641D01*
X1073786Y-17654D01*
G01X1072198Y-11375D02*
X1072920Y-10725D01*
X1073353Y-9967D01*
X1073497Y-8993D01*
X1073208Y-8019D01*
X1072631Y-7261D01*
X1071621Y-6719D01*
X1070466Y-6611D01*
X1069311Y-6828D01*
X1068589Y-7369D01*
X1068012Y-8127D01*
X1067867Y-8885D01*
X1068012Y-9643D01*
X1068589Y-10617D01*
X1064836Y-10292D01*
Y-7369D01*
G01Y-332D02*
X1065125Y-1198D01*
X1065846Y-1848D01*
X1066712Y-2281D01*
X1067867Y-2606D01*
X1069167Y-2714D01*
X1070466Y-2606D01*
X1071621Y-2281D01*
X1072487Y-1848D01*
X1073208Y-1198D01*
X1073497Y-332D01*
X1073208Y534D01*
X1072487Y1184D01*
X1071621Y1617D01*
X1070466Y1942D01*
X1069167Y2050D01*
X1067867Y1942D01*
X1066712Y1617D01*
X1065846Y1184D01*
X1065125Y534D01*
X1064836Y-332D01*
G01X1075662Y83489D02*
Y7247D01*
G01Y83489D02*
X1130387D01*
G01X1071725D02*
G03X1075662Y87426I0J3937D01*
G01X1071725Y83489D02*
G03X1075662Y87426I0J3937D01*
G01Y1969316D02*
Y87426D01*
G01Y1969316D02*
Y87426D01*
G01X1063576Y385024D02*
Y152032D01*
G01X1062276Y182028D02*
Y355028D01*
G01X1059276Y342528D02*
Y194528D01*
G01X1057276Y198528D02*
Y243528D01*
G01Y293528D02*
Y338528D01*
G01X1057354Y1901008D02*
Y1734079D01*
G01Y1901008D02*
Y1734079D01*
G01X1075662Y1969316D02*
G03X1071725Y1973253I-3937J0D01*
G01X1075662Y1969316D02*
G03X1071725Y1973253I-3937J0D01*
G01X1120419Y-80235D02*
X1121413Y-80046D01*
X1122549Y-79478D01*
X1123260Y-78531D01*
X1123544Y-77205D01*
X1123260Y-75880D01*
X1122407Y-74743D01*
X1121129Y-74175D01*
X1119709D01*
X1118857Y-73797D01*
X1118146Y-72850D01*
X1117862Y-71524D01*
X1118289Y-70199D01*
X1119283Y-69252D01*
X1120419Y-68873D01*
X1121555Y-69252D01*
X1122549Y-70199D01*
X1122976Y-71524D01*
X1122691Y-72850D01*
X1121981Y-73797D01*
X1121129Y-74175D01*
X1119709D01*
X1118431Y-74743D01*
X1117578Y-75880D01*
X1117294Y-77205D01*
X1117578Y-78531D01*
X1118289Y-79478D01*
X1119425Y-80046D01*
X1120419Y-80235D01*
G01X1145196Y-21867D02*
X1146063Y-22589D01*
X1147037Y-23022D01*
X1147903D01*
X1148769Y-22589D01*
X1149419Y-21867D01*
X1149744Y-20857D01*
X1149527Y-19846D01*
X1148986Y-18980D01*
X1148011Y-18403D01*
X1146712Y-18114D01*
X1145954Y-17537D01*
X1145629Y-16526D01*
X1145846Y-15516D01*
X1146387Y-14794D01*
X1147145Y-14361D01*
X1147903D01*
X1148661Y-14650D01*
X1149311Y-15371D01*
G01X1158513Y-15083D02*
X1157863Y-14650D01*
X1157105Y-14361D01*
X1156239D01*
X1155265Y-14794D01*
X1154507Y-15516D01*
X1153966Y-16382D01*
X1153532Y-17825D01*
X1153424Y-19125D01*
X1153641Y-20424D01*
X1153966Y-21290D01*
X1154615Y-22156D01*
X1155373Y-22733D01*
X1156131Y-23022D01*
X1156889D01*
X1157647Y-22733D01*
X1158296Y-22300D01*
X1158838Y-21723D01*
G01X1162085Y-23022D02*
X1164792Y-14361D01*
X1167499Y-23022D01*
G01X1166524Y-19991D02*
X1163060D01*
G01X1171288Y-14361D02*
Y-23022D01*
X1175618D01*
G01X1184279D02*
X1179949D01*
Y-14361D01*
X1184279D01*
G01X1182547Y-18547D02*
X1179949D01*
G01X1130366Y-2091D02*
X1129716Y-1658D01*
X1128958Y-1369D01*
X1128092D01*
X1127118Y-1802D01*
X1126360Y-2524D01*
X1125819Y-3390D01*
X1125385Y-4833D01*
X1125277Y-6133D01*
X1125494Y-7432D01*
X1125819Y-8298D01*
X1126468Y-9164D01*
X1127226Y-9741D01*
X1127984Y-10030D01*
X1128742D01*
X1129500Y-9741D01*
X1130149Y-9308D01*
X1130691Y-8731D01*
G01X1136645Y-10030D02*
X1135995Y-9886D01*
X1135346Y-9308D01*
X1134913Y-8298D01*
X1134696Y-7143D01*
X1134913Y-5988D01*
X1135346Y-4978D01*
X1135995Y-4400D01*
X1136645Y-4256D01*
X1137295Y-4400D01*
X1137944Y-4978D01*
X1138377Y-5988D01*
X1138486Y-7143D01*
X1138377Y-8298D01*
X1137944Y-9308D01*
X1137295Y-9886D01*
X1136645Y-10030D01*
G01X1142058D02*
Y-4256D01*
G01Y-5844D02*
X1142383Y-5122D01*
X1142924Y-4545D01*
X1143682Y-4256D01*
X1144440Y-4545D01*
X1144981Y-5122D01*
X1145306Y-5844D01*
Y-10030D01*
G01Y-5844D02*
X1145631Y-5122D01*
X1146172Y-4545D01*
X1146930Y-4256D01*
X1147688Y-4545D01*
X1148229Y-5122D01*
X1148554Y-5988D01*
Y-10030D01*
G01X1152018Y-12917D02*
Y-4256D01*
G01Y-5555D02*
X1152560Y-4833D01*
X1153101Y-4400D01*
X1153967Y-4256D01*
X1154725Y-4400D01*
X1155483Y-5122D01*
X1155808Y-6133D01*
X1155916Y-7143D01*
X1155808Y-8154D01*
X1155483Y-9164D01*
X1154833Y-9741D01*
X1153967Y-10030D01*
X1153209Y-9886D01*
X1152451Y-9453D01*
X1152018Y-8875D01*
G01X1162628Y-10030D02*
X1161978Y-9886D01*
X1161329Y-9308D01*
X1160896Y-8298D01*
X1160679Y-7143D01*
X1160896Y-5988D01*
X1161329Y-4978D01*
X1161978Y-4400D01*
X1162628Y-4256D01*
X1163278Y-4400D01*
X1163927Y-4978D01*
X1164360Y-5988D01*
X1164469Y-7143D01*
X1164360Y-8298D01*
X1163927Y-9308D01*
X1163278Y-9886D01*
X1162628Y-10030D01*
G01X1169448D02*
Y-4256D01*
G01Y-5700D02*
X1169882Y-4978D01*
X1170531Y-4400D01*
X1171397Y-4256D01*
X1172155Y-4400D01*
X1172805Y-4978D01*
X1173130Y-5988D01*
Y-10030D01*
G01X1178326Y-6133D02*
X1181791D01*
X1181466Y-5122D01*
X1180924Y-4545D01*
X1180167Y-4256D01*
X1179409Y-4400D01*
X1178759Y-4833D01*
X1178326Y-5844D01*
X1178109Y-6710D01*
Y-7576D01*
X1178326Y-8442D01*
X1178867Y-9308D01*
X1179517Y-9886D01*
X1180275Y-10030D01*
X1181033Y-9741D01*
X1181791Y-8875D01*
G01X1186770Y-10030D02*
Y-4256D01*
G01Y-5700D02*
X1187204Y-4978D01*
X1187853Y-4400D01*
X1188719Y-4256D01*
X1189477Y-4400D01*
X1190127Y-4978D01*
X1190452Y-5988D01*
Y-10030D01*
G01X1197272Y-1369D02*
Y-10030D01*
G01X1195756Y-4256D02*
X1198788D01*
G01X1212320Y-8875D02*
X1213187Y-9597D01*
X1214161Y-10030D01*
X1215027D01*
X1215893Y-9597D01*
X1216543Y-8875D01*
X1216868Y-7865D01*
X1216651Y-6854D01*
X1216110Y-5988D01*
X1215135Y-5411D01*
X1213836Y-5122D01*
X1213078Y-4545D01*
X1212753Y-3534D01*
X1212970Y-2524D01*
X1213511Y-1802D01*
X1214269Y-1369D01*
X1215027D01*
X1215785Y-1658D01*
X1216435Y-2379D01*
G01X1223255Y-4256D02*
Y-10030D01*
G01Y-1947D02*
X1223038Y-1802D01*
Y-1513D01*
X1223255Y-1369D01*
X1223472Y-1513D01*
Y-1802D01*
X1223255Y-1947D01*
G01X1233865Y-1369D02*
Y-10030D01*
G01Y-8731D02*
X1233432Y-9453D01*
X1232782Y-9886D01*
X1232024Y-10030D01*
X1231158Y-9741D01*
X1230509Y-9020D01*
X1230075Y-8154D01*
X1229967Y-7143D01*
X1230075Y-6133D01*
X1230509Y-5266D01*
X1231158Y-4545D01*
X1232024Y-4256D01*
X1232782Y-4400D01*
X1233323Y-4689D01*
X1233865Y-5266D01*
G01X1238953Y-6133D02*
X1242418D01*
X1242093Y-5122D01*
X1241551Y-4545D01*
X1240794Y-4256D01*
X1240036Y-4400D01*
X1239386Y-4833D01*
X1238953Y-5844D01*
X1238736Y-6710D01*
Y-7576D01*
X1238953Y-8442D01*
X1239494Y-9308D01*
X1240144Y-9886D01*
X1240902Y-10030D01*
X1241660Y-9741D01*
X1242418Y-8875D01*
G01X1137965Y85654D02*
Y94315D01*
X1136666Y92583D01*
G01Y85654D02*
X1139264D01*
G01X1146626Y94315D02*
X1145760Y94026D01*
X1145110Y93305D01*
X1144677Y92439D01*
X1144352Y91284D01*
X1144244Y89984D01*
X1144352Y88685D01*
X1144677Y87530D01*
X1145110Y86664D01*
X1145760Y85943D01*
X1146626Y85654D01*
X1147492Y85943D01*
X1148142Y86664D01*
X1148575Y87530D01*
X1148900Y88685D01*
X1149008Y89984D01*
X1148900Y91284D01*
X1148575Y92439D01*
X1148142Y93305D01*
X1147492Y94026D01*
X1146626Y94315D01*
G01X1155287Y85365D02*
X1155070Y85510D01*
Y85798D01*
X1155287Y85943D01*
X1155504Y85798D01*
Y85510D01*
X1155287Y85365D01*
G01X1163948Y94315D02*
X1163082Y94026D01*
X1162432Y93305D01*
X1161999Y92439D01*
X1161674Y91284D01*
X1161566Y89984D01*
X1161674Y88685D01*
X1161999Y87530D01*
X1162432Y86664D01*
X1163082Y85943D01*
X1163948Y85654D01*
X1164814Y85943D01*
X1165464Y86664D01*
X1165897Y87530D01*
X1166222Y88685D01*
X1166330Y89984D01*
X1166222Y91284D01*
X1165897Y92439D01*
X1165464Y93305D01*
X1164814Y94026D01*
X1163948Y94315D01*
G01X1172609D02*
X1171743Y94026D01*
X1171093Y93305D01*
X1170660Y92439D01*
X1170335Y91284D01*
X1170227Y89984D01*
X1170335Y88685D01*
X1170660Y87530D01*
X1171093Y86664D01*
X1171743Y85943D01*
X1172609Y85654D01*
X1173475Y85943D01*
X1174125Y86664D01*
X1174558Y87530D01*
X1174883Y88685D01*
X1174991Y89984D01*
X1174883Y91284D01*
X1174558Y92439D01*
X1174125Y93305D01*
X1173475Y94026D01*
X1172609Y94315D01*
G01X1120419Y2097521D02*
X1121413Y2097710D01*
X1122549Y2098278D01*
X1123260Y2099225D01*
X1123544Y2100551D01*
X1123260Y2101876D01*
X1122407Y2103013D01*
X1121129Y2103581D01*
X1119709D01*
X1118857Y2103959D01*
X1118146Y2104906D01*
X1117862Y2106232D01*
X1118289Y2107557D01*
X1119283Y2108504D01*
X1120419Y2108883D01*
X1121555Y2108504D01*
X1122549Y2107557D01*
X1122976Y2106232D01*
X1122691Y2104906D01*
X1121981Y2103959D01*
X1121129Y2103581D01*
X1119709D01*
X1118431Y2103013D01*
X1117578Y2101876D01*
X1117294Y2100551D01*
X1117578Y2099225D01*
X1118289Y2098278D01*
X1119425Y2097710D01*
X1120419Y2097521D01*
G01X1194242Y-23022D02*
Y-14361D01*
X1192943Y-16093D01*
G01Y-23022D02*
X1195541D01*
G01X1202903Y-23311D02*
X1202686Y-23166D01*
Y-22878D01*
X1202903Y-22733D01*
X1203120Y-22878D01*
Y-23166D01*
X1202903Y-23311D01*
G01X1211564Y-14361D02*
X1210698Y-14650D01*
X1210048Y-15371D01*
X1209615Y-16237D01*
X1209290Y-17392D01*
X1209182Y-18692D01*
X1209290Y-19991D01*
X1209615Y-21146D01*
X1210048Y-22012D01*
X1210698Y-22733D01*
X1211564Y-23022D01*
X1212430Y-22733D01*
X1213080Y-22012D01*
X1213513Y-21146D01*
X1213838Y-19991D01*
X1213946Y-18692D01*
X1213838Y-17392D01*
X1213513Y-16237D01*
X1213080Y-15371D01*
X1212430Y-14650D01*
X1211564Y-14361D01*
G01X1220225D02*
X1219359Y-14650D01*
X1218709Y-15371D01*
X1218276Y-16237D01*
X1217951Y-17392D01*
X1217843Y-18692D01*
X1217951Y-19991D01*
X1218276Y-21146D01*
X1218709Y-22012D01*
X1219359Y-22733D01*
X1220225Y-23022D01*
X1221091Y-22733D01*
X1221741Y-22012D01*
X1222174Y-21146D01*
X1222499Y-19991D01*
X1222607Y-18692D01*
X1222499Y-17392D01*
X1222174Y-16237D01*
X1221741Y-15371D01*
X1221091Y-14650D01*
X1220225Y-14361D01*
G01X1228886D02*
X1228020Y-14650D01*
X1227370Y-15371D01*
X1226937Y-16237D01*
X1226612Y-17392D01*
X1226504Y-18692D01*
X1226612Y-19991D01*
X1226937Y-21146D01*
X1227370Y-22012D01*
X1228020Y-22733D01*
X1228886Y-23022D01*
X1229752Y-22733D01*
X1230402Y-22012D01*
X1230835Y-21146D01*
X1231160Y-19991D01*
X1231268Y-18692D01*
X1231160Y-17392D01*
X1230835Y-16237D01*
X1230402Y-15371D01*
X1229752Y-14650D01*
X1228886Y-14361D01*
G01X1229780Y-65085D02*
Y-84022D01*
G01Y2112671D02*
Y2093734D01*
G01X1337673Y-78910D02*
X1338668Y-79856D01*
X1339804Y-80235D01*
X1340940Y-79856D01*
X1341934Y-78720D01*
X1342645Y-77016D01*
X1342929Y-75311D01*
Y-73229D01*
X1342645Y-71524D01*
X1341934Y-70009D01*
X1341082Y-69252D01*
X1340088Y-68873D01*
X1338952Y-69252D01*
X1338100Y-70009D01*
X1337531Y-71145D01*
X1337247Y-72661D01*
X1337531Y-73986D01*
X1338242Y-75311D01*
X1339094Y-76069D01*
X1340088Y-76258D01*
X1341224Y-75880D01*
X1342076Y-74933D01*
X1342929Y-73229D01*
G01X1337673Y2098846D02*
X1338668Y2097900D01*
X1339804Y2097521D01*
X1340940Y2097900D01*
X1341934Y2099036D01*
X1342645Y2100740D01*
X1342929Y2102445D01*
Y2104527D01*
X1342645Y2106232D01*
X1341934Y2107747D01*
X1341082Y2108504D01*
X1340088Y2108883D01*
X1338952Y2108504D01*
X1338100Y2107747D01*
X1337531Y2106611D01*
X1337247Y2105095D01*
X1337531Y2103770D01*
X1338242Y2102445D01*
X1339094Y2101687D01*
X1340088Y2101498D01*
X1341224Y2101876D01*
X1342076Y2102823D01*
X1342929Y2104527D01*
G01X1449449Y-65085D02*
Y-84022D01*
G01X1452019Y61474D02*
G03X1455956Y57537I3937J0D01*
G01X1452019Y61474D02*
G03X1455956Y57537I3937J0D01*
G01X1497688Y82341D02*
G03I-15748J0D01*
G01X1452019Y61474D02*
Y2022104D01*
G01Y61474D02*
Y2022104D01*
G01X1516980Y57537D02*
X1455956D01*
G01X1516980D02*
X1455956D01*
G01X1497688Y168955D02*
G03I-15748J0D01*
G01X1495326Y215018D02*
G03I-15748J0D01*
G01X1497688Y515569D02*
G03I-15748J0D01*
G01Y602183D02*
G03I-15748J0D01*
G01X1495326Y687459D02*
G03I-15748J0D01*
G01X1497688Y775411D02*
G03I-15748J0D01*
G01Y862026D02*
G03I-15748J0D01*
G01Y1221553D02*
G03I-15748J0D01*
G01Y1308167D02*
G03I-15748J0D01*
G01X1476625Y1396120D02*
G03I-6889J0D01*
G01X1485484D02*
G03I-15748J0D01*
G01X1497688Y1481396D02*
G03I-15748J0D01*
G01Y1568010D02*
G03I-15748J0D01*
G01X1495326Y1868561D02*
G03I-15748J0D01*
G01X1497688Y1914624D02*
G03I-15748J0D01*
G01X1455956Y2026041D02*
G03X1452019Y2022104I0J-3937D01*
G01X1455956Y2026041D02*
G03X1452019Y2022104I0J-3937D01*
G01X1497688Y2001238D02*
G03I-15748J0D01*
G01X1455956Y2026041D02*
X1516980D01*
G01X1455956D02*
X1516980D01*
G01X1449449Y2112671D02*
Y2093734D01*
G01X1513280Y-65085D02*
X1903043D01*
G01X1509176Y-5878D02*
X1510043Y-6600D01*
X1511017Y-7033D01*
X1511883D01*
X1512749Y-6600D01*
X1513399Y-5878D01*
X1513724Y-4868D01*
X1513507Y-3857D01*
X1512966Y-2991D01*
X1511991Y-2414D01*
X1510692Y-2125D01*
X1509934Y-1548D01*
X1509609Y-537D01*
X1509826Y473D01*
X1510367Y1195D01*
X1511125Y1628D01*
X1511883D01*
X1512641Y1339D01*
X1513291Y618D01*
G01X1522493Y906D02*
X1521843Y1339D01*
X1521085Y1628D01*
X1520219D01*
X1519245Y1195D01*
X1518487Y473D01*
X1517946Y-393D01*
X1517512Y-1836D01*
X1517404Y-3136D01*
X1517621Y-4435D01*
X1517946Y-5301D01*
X1518595Y-6167D01*
X1519353Y-6744D01*
X1520111Y-7033D01*
X1520869D01*
X1521627Y-6744D01*
X1522276Y-6311D01*
X1522818Y-5734D01*
G01X1526065Y-7033D02*
X1528772Y1628D01*
X1531479Y-7033D01*
G01X1530504Y-4002D02*
X1527040D01*
G01X1535268Y1628D02*
Y-7033D01*
X1539598D01*
G01X1548259D02*
X1543929D01*
Y1628D01*
X1548259D01*
G01X1546527Y-2558D02*
X1543929D01*
G01X1502681Y7114D02*
X1503548Y6392D01*
X1504522Y5959D01*
X1505388D01*
X1506254Y6392D01*
X1506904Y7114D01*
X1507229Y8124D01*
X1507012Y9135D01*
X1506471Y10001D01*
X1505496Y10578D01*
X1504197Y10867D01*
X1503439Y11444D01*
X1503114Y12455D01*
X1503331Y13465D01*
X1503872Y14187D01*
X1504630Y14620D01*
X1505388D01*
X1506146Y14331D01*
X1506796Y13610D01*
G01X1513616Y5959D02*
X1512966Y6103D01*
X1512317Y6681D01*
X1511884Y7691D01*
X1511667Y8846D01*
X1511884Y10001D01*
X1512317Y11011D01*
X1512966Y11589D01*
X1513616Y11733D01*
X1514266Y11589D01*
X1514915Y11011D01*
X1515348Y10001D01*
X1515457Y8846D01*
X1515348Y7691D01*
X1514915Y6681D01*
X1514266Y6103D01*
X1513616Y5959D01*
G01X1522277D02*
Y14620D01*
G01X1532887D02*
Y5959D01*
G01Y7258D02*
X1532454Y6536D01*
X1531804Y6103D01*
X1531046Y5959D01*
X1530180Y6248D01*
X1529531Y6969D01*
X1529097Y7835D01*
X1528989Y8846D01*
X1529097Y9856D01*
X1529531Y10723D01*
X1530180Y11444D01*
X1531046Y11733D01*
X1531804Y11589D01*
X1532345Y11300D01*
X1532887Y10723D01*
G01X1537975Y9856D02*
X1541440D01*
X1541115Y10867D01*
X1540573Y11444D01*
X1539816Y11733D01*
X1539058Y11589D01*
X1538408Y11156D01*
X1537975Y10145D01*
X1537758Y9279D01*
Y8413D01*
X1537975Y7547D01*
X1538516Y6681D01*
X1539166Y6103D01*
X1539924Y5959D01*
X1540682Y6248D01*
X1541440Y7114D01*
G01X1546744Y5959D02*
Y11733D01*
G01Y10578D02*
X1547286Y11156D01*
X1547827Y11589D01*
X1548585Y11733D01*
X1549126Y11589D01*
X1549776Y11156D01*
G01X1563308Y7114D02*
X1564175Y6392D01*
X1565149Y5959D01*
X1566015D01*
X1566881Y6392D01*
X1567531Y7114D01*
X1567856Y8124D01*
X1567639Y9135D01*
X1567098Y10001D01*
X1566123Y10578D01*
X1564824Y10867D01*
X1564066Y11444D01*
X1563741Y12455D01*
X1563958Y13465D01*
X1564499Y14187D01*
X1565257Y14620D01*
X1566015D01*
X1566773Y14331D01*
X1567423Y13610D01*
G01X1574243Y11733D02*
Y5959D01*
G01Y14042D02*
X1574026Y14187D01*
Y14476D01*
X1574243Y14620D01*
X1574460Y14476D01*
Y14187D01*
X1574243Y14042D01*
G01X1584853Y14620D02*
Y5959D01*
G01Y7258D02*
X1584420Y6536D01*
X1583770Y6103D01*
X1583012Y5959D01*
X1582146Y6248D01*
X1581497Y6969D01*
X1581063Y7835D01*
X1580955Y8846D01*
X1581063Y9856D01*
X1581497Y10723D01*
X1582146Y11444D01*
X1583012Y11733D01*
X1583770Y11589D01*
X1584311Y11300D01*
X1584853Y10723D01*
G01X1589941Y9856D02*
X1593406D01*
X1593081Y10867D01*
X1592539Y11444D01*
X1591782Y11733D01*
X1591024Y11589D01*
X1590374Y11156D01*
X1589941Y10145D01*
X1589724Y9279D01*
Y8413D01*
X1589941Y7547D01*
X1590482Y6681D01*
X1591132Y6103D01*
X1591890Y5959D01*
X1592648Y6248D01*
X1593406Y7114D01*
G01X1516980Y57537D02*
G03X1520917Y61474I0J3937D01*
G01X1516980Y57537D02*
G03X1520917Y61474I0J3937D01*
G01X1489027Y82341D02*
G03I-7087J0D01*
G01X1504972Y125648D02*
G03I-5709J0D01*
G01X1489027Y168955D02*
G03I-7087J0D01*
G01X1487452Y215018D02*
G03I-7874J0D01*
G01X1489027Y515569D02*
G03I-7087J0D01*
G01X1504972Y558876D02*
G03I-5709J0D01*
G01X1489027Y602183D02*
G03I-7087J0D01*
G01X1486468Y687459D02*
G03I-6890J0D01*
G01X1489027Y775411D02*
G03I-7087J0D01*
G01X1504972Y818719D02*
G03I-5709J0D01*
G01X1489027Y862026D02*
G03I-7087J0D01*
G01Y1221553D02*
G03I-7087J0D01*
G01X1504972Y1264860D02*
G03I-5709J0D01*
G01X1489027Y1308167D02*
G03I-7087J0D01*
G01X1504972Y1524703D02*
G03I-5709J0D01*
G01X1489027Y1481396D02*
G03I-7087J0D01*
G01Y1568010D02*
G03I-7087J0D01*
G01X1486468Y1868561D02*
G03I-6890J0D01*
G01X1489027Y1914624D02*
G03I-7087J0D01*
G01X1504972Y1957931D02*
G03I-5709J0D01*
G01X1520917Y2022104D02*
G03X1516980Y2026041I-3937J0D01*
G01X1520917Y2022104D02*
G03X1516980Y2026041I-3937J0D01*
G01X1489027Y2001238D02*
G03I-7087J0D01*
G01X1557106Y-80235D02*
Y-68873D01*
X1555402Y-71145D01*
G01Y-80235D02*
X1558810D01*
G01X1568469Y-68873D02*
X1567333Y-69252D01*
X1566481Y-70199D01*
X1565912Y-71335D01*
X1565486Y-72850D01*
X1565344Y-74554D01*
X1565486Y-76258D01*
X1565912Y-77773D01*
X1566481Y-78910D01*
X1567333Y-79856D01*
X1568469Y-80235D01*
X1569605Y-79856D01*
X1570457Y-78910D01*
X1571026Y-77773D01*
X1571452Y-76258D01*
X1571594Y-74554D01*
X1571452Y-72850D01*
X1571026Y-71335D01*
X1570457Y-70199D01*
X1569605Y-69252D01*
X1568469Y-68873D01*
G01X1558221Y-7033D02*
Y1628D01*
X1556922Y-104D01*
G01Y-7033D02*
X1559520D01*
G01X1566882Y-7322D02*
X1566665Y-7177D01*
Y-6889D01*
X1566882Y-6744D01*
X1567099Y-6889D01*
Y-7177D01*
X1566882Y-7322D01*
G01X1575543Y1628D02*
X1574677Y1339D01*
X1574027Y618D01*
X1573594Y-248D01*
X1573269Y-1403D01*
X1573161Y-2703D01*
X1573269Y-4002D01*
X1573594Y-5157D01*
X1574027Y-6023D01*
X1574677Y-6744D01*
X1575543Y-7033D01*
X1576409Y-6744D01*
X1577059Y-6023D01*
X1577492Y-5157D01*
X1577817Y-4002D01*
X1577925Y-2703D01*
X1577817Y-1403D01*
X1577492Y-248D01*
X1577059Y618D01*
X1576409Y1339D01*
X1575543Y1628D01*
G01X1584204D02*
X1583338Y1339D01*
X1582688Y618D01*
X1582255Y-248D01*
X1581930Y-1403D01*
X1581822Y-2703D01*
X1581930Y-4002D01*
X1582255Y-5157D01*
X1582688Y-6023D01*
X1583338Y-6744D01*
X1584204Y-7033D01*
X1585070Y-6744D01*
X1585720Y-6023D01*
X1586153Y-5157D01*
X1586478Y-4002D01*
X1586586Y-2703D01*
X1586478Y-1403D01*
X1586153Y-248D01*
X1585720Y618D01*
X1585070Y1339D01*
X1584204Y1628D01*
G01X1592865D02*
X1591999Y1339D01*
X1591349Y618D01*
X1590916Y-248D01*
X1590591Y-1403D01*
X1590483Y-2703D01*
X1590591Y-4002D01*
X1590916Y-5157D01*
X1591349Y-6023D01*
X1591999Y-6744D01*
X1592865Y-7033D01*
X1593731Y-6744D01*
X1594381Y-6023D01*
X1594814Y-5157D01*
X1595139Y-4002D01*
X1595247Y-2703D01*
X1595139Y-1403D01*
X1594814Y-248D01*
X1594381Y618D01*
X1593731Y1339D01*
X1592865Y1628D01*
G01X1520917Y92971D02*
Y61474D01*
G01Y92971D02*
Y61474D01*
G01X1524854Y96908D02*
G03X1520917Y92971I0J-3937D01*
G01X1524854Y96908D02*
G03X1520917Y92971I0J-3937D01*
G01X1654775Y96908D02*
X1524854D01*
G01X1654775D02*
X1524854D01*
G01X1559868Y1196107D02*
X1558193Y1196869D01*
G01X1555680Y1217286D02*
X1559868Y1215792D01*
G01D02*
X1579972Y1216494D01*
G01Y1209932D02*
X1553167Y1208996D01*
G01X1559030Y1205100D02*
X1579972Y1205831D01*
G01X1553167Y1204895D02*
X1555680Y1204983D01*
G01X1579972Y1196809D02*
X1559868Y1196107D01*
G01Y1192006D02*
X1579972Y1192708D01*
G01Y1183686D02*
X1559868Y1182984D01*
G01X1558193Y1196869D02*
X1557355Y1197660D01*
G01X1554004Y1195082D02*
X1556517Y1192709D01*
G01X1558193Y1183745D02*
X1557355Y1184536D01*
G01X1554004Y1181959D02*
X1555680Y1180377D01*
G01X1559868Y1182984D02*
X1558193Y1183745D01*
G01X1555680Y1180377D02*
X1559868Y1178883D01*
G01D02*
X1579972Y1179585D01*
G01X1553167Y1197513D02*
X1554004Y1195082D01*
G01X1553167Y1184390D02*
X1554004Y1181959D01*
G01X1557355Y1197660D02*
X1556517Y1199271D01*
G01X1557355Y1184536D02*
X1556517Y1186148D01*
G01X1554004Y1190161D02*
X1553167Y1187671D01*
G01X1556517Y1200911D02*
X1557355Y1203401D01*
G01X1554004Y1203284D02*
X1553167Y1200794D01*
G01X1556517Y1199271D02*
Y1200911D01*
G01Y1186148D02*
Y1188608D01*
G01X1553167Y1187671D02*
Y1184390D01*
G01Y1200794D02*
Y1197513D01*
G01Y1208996D02*
Y1204895D01*
G01X1557355Y1190278D02*
X1558193Y1191127D01*
G01X1556517Y1192709D02*
X1554004Y1190161D01*
G01X1557355Y1203401D02*
X1559030Y1205100D01*
G01X1555680Y1204983D02*
X1554004Y1203284D01*
G01X1556517Y1188608D02*
X1557355Y1190278D01*
G01X1558193Y1191127D02*
X1559868Y1192006D01*
G01X1556517Y1252585D02*
X1552329Y1253259D01*
G01X1557355Y1256715D02*
X1552329Y1257360D01*
G01X1563219Y1256920D02*
X1557355Y1256715D01*
G01X1564056Y1252848D02*
X1556517Y1252585D01*
G01X1568245Y1257915D02*
X1563219Y1256920D01*
G01X1546465Y1255514D02*
X1543952Y1257887D01*
G01X1558193Y1233778D02*
X1557355Y1234569D01*
G01X1552329Y1257360D02*
X1547303Y1260465D01*
G01X1549816Y1253991D02*
X1546465Y1255514D01*
G01X1559868Y1233017D02*
X1558193Y1233778D01*
G01X1559868Y1219893D02*
X1558193Y1220655D01*
G01X1552329Y1253259D02*
X1549816Y1253991D01*
G01X1579972Y1246842D02*
X1553167Y1245906D01*
G01X1559030Y1242010D02*
X1579972Y1242741D01*
G01X1553167Y1241805D02*
X1555680Y1241893D01*
G01X1579972Y1233719D02*
X1559868Y1233017D01*
G01Y1228915D02*
X1579972Y1229618D01*
G01Y1220595D02*
X1559868Y1219893D01*
G01X1568245Y1253814D02*
X1564056Y1252848D01*
G01X1557355Y1234569D02*
X1556517Y1236180D01*
G01X1557355Y1221446D02*
X1556517Y1223057D01*
G01X1543952Y1257887D02*
X1541439Y1261901D01*
G01X1547303Y1260465D02*
X1545628Y1262867D01*
G01X1554004Y1231992D02*
X1556517Y1229619D01*
G01X1558193Y1220655D02*
X1557355Y1221446D01*
G01X1554004Y1218868D02*
X1555680Y1217286D01*
G01X1541439Y1261901D02*
X1540602Y1266793D01*
G01X1545628Y1262867D02*
X1544790Y1266939D01*
G01X1553167Y1234423D02*
X1554004Y1231992D01*
G01X1553167Y1221300D02*
X1554004Y1218868D01*
G01X1544790Y1266939D02*
X1545628Y1271069D01*
G01X1540602Y1266793D02*
X1541439Y1271743D01*
G01X1556517Y1236180D02*
Y1237821D01*
G01Y1223057D02*
Y1225518D01*
G01X1553167Y1224580D02*
Y1221300D01*
G01Y1237704D02*
Y1234423D01*
G01Y1245906D02*
Y1241805D01*
G01X1556517Y1225518D02*
X1557355Y1227187D01*
G01X1554004Y1227070D02*
X1553167Y1224580D01*
G01X1556517Y1237821D02*
X1557355Y1240311D01*
G01X1554004Y1240194D02*
X1553167Y1237704D01*
G01X1558193Y1228037D02*
X1559868Y1228915D01*
G01X1573271Y1261372D02*
X1568245Y1257915D01*
G01X1557355Y1227187D02*
X1558193Y1228037D01*
G01X1556517Y1229619D02*
X1554004Y1227070D01*
G01X1557355Y1240311D02*
X1559030Y1242010D01*
G01X1555680Y1241893D02*
X1554004Y1240194D01*
G01X1570758Y1254722D02*
X1568245Y1253814D01*
G01Y1277600D02*
X1573271Y1274495D01*
G01X1568245Y1281701D02*
X1570758Y1280969D01*
G01X1564056Y1282375D02*
X1568245Y1281701D01*
G01X1563219Y1278245D02*
X1568245Y1277600D01*
G01X1547303Y1312138D02*
X1563219Y1312694D01*
G01X1579972Y1313279D02*
X1568245Y1312869D01*
G01Y1307948D02*
X1579972Y1308358D01*
G01X1540602Y1306983D02*
X1563219Y1307773D01*
G01Y1299571D02*
X1568245Y1299746D01*
G01X1556517Y1282112D02*
X1564056Y1282375D01*
G01X1557355Y1278040D02*
X1563219Y1278245D01*
G01X1552329Y1277045D02*
X1557355Y1278040D01*
G01X1552329Y1281146D02*
X1556517Y1282112D01*
G01X1568245Y1312869D02*
Y1332554D01*
G01Y1299746D02*
Y1307948D01*
G01X1563219Y1312694D02*
Y1326637D01*
G01Y1307773D02*
Y1299571D01*
G01X1540602Y1311904D02*
Y1306983D01*
G01X1543952Y1275932D02*
X1546465Y1278480D01*
G01X1545628Y1271069D02*
X1547303Y1273588D01*
G01X1541439Y1271743D02*
X1543952Y1275932D01*
G01X1549816Y1280238D02*
X1552329Y1281146D01*
G01X1546465Y1278480D02*
X1549816Y1280238D01*
G01X1547303Y1273588D02*
X1552329Y1277045D01*
G01X1563219Y1332379D02*
X1540602Y1311904D01*
G01X1563219Y1326637D02*
X1547303Y1312138D01*
G01X1556517Y1367414D02*
X1540602Y1366858D01*
G01X1579972Y1368233D02*
X1561543Y1367589D01*
G01X1540602Y1361937D02*
X1579972Y1363312D01*
G01X1568245Y1332554D02*
X1563219Y1332379D01*
G01X1551491Y1340172D02*
X1554004Y1338619D01*
G01X1559868Y1350307D02*
X1565732Y1339028D01*
G01X1568245Y1340757D02*
X1559868Y1356048D01*
G01X1561543Y1367589D02*
Y1390555D01*
G01X1556517Y1390380D02*
Y1367414D01*
G01X1540602Y1366858D02*
Y1361937D01*
G01X1559868Y1356048D02*
X1551491Y1340172D01*
G01X1554004Y1338619D02*
X1559868Y1350307D01*
G01X1565732Y1339028D02*
X1568245Y1340757D01*
G01X1579972Y1396120D02*
X1540602Y1394745D01*
G01X1561543Y1390555D02*
X1579972Y1391199D01*
G01X1540602Y1389824D02*
X1556517Y1390380D01*
G01X1540602Y1394745D02*
Y1389824D01*
G01X1558318Y1805372D02*
G03I-9842J0D01*
G01X1567177D02*
G03I-18701J0D01*
G01X1558318Y1880569D02*
G03I-9842J0D01*
G01X1567177D02*
G03I-18701J0D01*
G01X1520917Y1990608D02*
G03X1524854Y1986671I3937J0D01*
G01X1520917Y1990608D02*
G03X1524854Y1986671I3937J0D01*
G01D02*
X1654775D01*
G01X1524854D02*
X1654775D01*
G01X1520917Y2022104D02*
Y1990608D01*
G01Y2022104D02*
Y1990608D01*
G01X1557106Y2097521D02*
Y2108883D01*
X1555402Y2106611D01*
G01Y2097521D02*
X1558810D01*
G01X1568469Y2108883D02*
X1567333Y2108504D01*
X1566481Y2107557D01*
X1565912Y2106421D01*
X1565486Y2104906D01*
X1565344Y2103202D01*
X1565486Y2101498D01*
X1565912Y2099983D01*
X1566481Y2098846D01*
X1567333Y2097900D01*
X1568469Y2097521D01*
X1569605Y2097900D01*
X1570457Y2098846D01*
X1571026Y2099983D01*
X1571452Y2101498D01*
X1571594Y2103202D01*
X1571452Y2104906D01*
X1571026Y2106421D01*
X1570457Y2107557D01*
X1569605Y2108504D01*
X1568469Y2108883D01*
G01X1646901Y136278D02*
G03I-15748J0D01*
G01Y628404D02*
G03I-15748J0D01*
G01Y1218955D02*
G03I-15748J0D01*
G01X1579972Y1216494D02*
Y1220595D01*
G01Y1205831D02*
Y1209932D01*
G01Y1192708D02*
Y1196809D01*
G01Y1179585D02*
Y1183686D01*
G01X1579134Y1273059D02*
X1579972Y1268167D01*
G01X1574946Y1272093D02*
X1575784Y1268021D01*
G01X1579972Y1242741D02*
Y1246842D01*
G01Y1229618D02*
Y1233719D01*
G01X1575784Y1268021D02*
X1574946Y1263891D01*
G01X1579972Y1268167D02*
X1579134Y1263217D01*
G01X1574946Y1263891D02*
X1573271Y1261372D01*
G01X1579134Y1263217D02*
X1576621Y1259028D01*
G01X1574108Y1256480D02*
X1570758Y1254722D01*
G01X1576621Y1259028D02*
X1574108Y1256480D01*
G01X1570758Y1280969D02*
X1574108Y1279446D01*
G01X1579972Y1293594D02*
X1575784Y1293448D01*
G01Y1289347D02*
X1579972Y1289493D01*
G01X1576621Y1277073D02*
X1579134Y1273059D01*
G01X1573271Y1274495D02*
X1574946Y1272093D01*
G01X1574108Y1279446D02*
X1576621Y1277073D01*
G01X1579972Y1308358D02*
Y1313279D01*
G01Y1289493D02*
Y1293594D01*
G01X1575784Y1293448D02*
Y1289347D01*
G01X1579972Y1363312D02*
Y1368233D01*
G01X1649657Y1386278D02*
G03I-18701J0D01*
G01X1579972Y1391199D02*
Y1396120D01*
G01X1623279Y1805372D02*
G03I-9843J0D01*
G01X1632137D02*
G03I-18701J0D01*
G01X1623279Y1880569D02*
G03I-9843J0D01*
G01X1632137D02*
G03I-18701J0D01*
G01X1646901Y1947301D02*
G03I-15748J0D01*
G01X1669118Y-65085D02*
Y-84022D01*
G01X1654775Y96908D02*
G03X1658712Y100845I0J3937D01*
G01X1654775Y96908D02*
G03X1658712Y100845I0J3937D01*
G01X1638043Y136278D02*
G03I-6890J0D01*
G01X1658712Y1982734D02*
Y100845D01*
G01Y1982734D02*
Y100845D01*
G01X1638043Y628404D02*
G03I-6890J0D01*
G01Y1218955D02*
G03I-6890J0D01*
G01X1640799Y1386278D02*
G03I-9843J0D01*
G01X1658712Y1982734D02*
G03X1654775Y1986671I-3937J0D01*
G01X1658712Y1982734D02*
G03X1654775Y1986671I-3937J0D01*
G01X1639027Y1947301D02*
G03I-7874J0D01*
G01X1669118Y2112671D02*
Y2093734D01*
G01X1714894D02*
X2222768D01*
G01X1777533Y-80235D02*
Y-68873D01*
X1775829Y-71145D01*
G01Y-80235D02*
X1779237D01*
G01X1788896D02*
Y-68873D01*
X1787192Y-71145D01*
G01Y-80235D02*
X1790600D01*
G01X1747369Y18968D02*
Y-41200D01*
G01D02*
X2499470D01*
G01X1774908Y46365D02*
X1773408Y47365D01*
X1771658Y48032D01*
X1769658D01*
X1767408Y47032D01*
X1765658Y45365D01*
X1764408Y43365D01*
X1763408Y40032D01*
X1763158Y37032D01*
X1763658Y34032D01*
X1764408Y32032D01*
X1765908Y30032D01*
X1767658Y28699D01*
X1769408Y28032D01*
X1771158D01*
X1772908Y28699D01*
X1774408Y29698D01*
X1775658Y31031D01*
G01X1785908Y28032D02*
Y41365D01*
G01Y38699D02*
X1787158Y40032D01*
X1788408Y41032D01*
X1790158Y41365D01*
X1791408Y41032D01*
X1792908Y40032D01*
G01X1805658Y37032D02*
X1813658D01*
X1812908Y39365D01*
X1811658Y40698D01*
X1809908Y41365D01*
X1808158Y41032D01*
X1806658Y40032D01*
X1805658Y37698D01*
X1805158Y35698D01*
Y33699D01*
X1805658Y31698D01*
X1806908Y29698D01*
X1808408Y28365D01*
X1810158Y28032D01*
X1811908Y28699D01*
X1813658Y30698D01*
G01X1833908Y28032D02*
Y41365D01*
G01Y39032D02*
X1832908Y40365D01*
X1831408Y41032D01*
X1829658Y41365D01*
X1827908Y40698D01*
X1826408Y39365D01*
X1825408Y37365D01*
X1824908Y34698D01*
X1825408Y32032D01*
X1826408Y30032D01*
X1827908Y28699D01*
X1829658Y28032D01*
X1831408Y28365D01*
X1832908Y29365D01*
X1833908Y30698D01*
G01X1849408Y48032D02*
Y28032D01*
G01X1845908Y41365D02*
X1852908D01*
G01X1865658Y37032D02*
X1873658D01*
X1872908Y39365D01*
X1871658Y40698D01*
X1869908Y41365D01*
X1868158Y41032D01*
X1866658Y40032D01*
X1865658Y37698D01*
X1865158Y35698D01*
Y33699D01*
X1865658Y31698D01*
X1866908Y29698D01*
X1868408Y28365D01*
X1870158Y28032D01*
X1871908Y28699D01*
X1873658Y30698D01*
G01X1893908Y48032D02*
Y28032D01*
G01Y31031D02*
X1892908Y29365D01*
X1891408Y28365D01*
X1889658Y28032D01*
X1887658Y28699D01*
X1886158Y30365D01*
X1885158Y32365D01*
X1884908Y34698D01*
X1885158Y37032D01*
X1886158Y39032D01*
X1887658Y40698D01*
X1889658Y41365D01*
X1891408Y41032D01*
X1892658Y40365D01*
X1893908Y39032D01*
G01X1747369Y18968D02*
Y64094D01*
G01X2537075Y18968D02*
X1747369D01*
G01X1760456Y96940D02*
X1766706Y76940D01*
X1772956Y96940D01*
G01X1782956Y85940D02*
X1790956D01*
X1790206Y88273D01*
X1788956Y89606D01*
X1787206Y90273D01*
X1785456Y89940D01*
X1783956Y88940D01*
X1782956Y86606D01*
X1782456Y84606D01*
Y82607D01*
X1782956Y80606D01*
X1784206Y78606D01*
X1785706Y77273D01*
X1787456Y76940D01*
X1789206Y77607D01*
X1790956Y79606D01*
G01X1803206Y76940D02*
Y90273D01*
G01Y87607D02*
X1804456Y88940D01*
X1805706Y89940D01*
X1807456Y90273D01*
X1808706Y89940D01*
X1810206Y88940D01*
G01X1822956Y79273D02*
X1824206Y77940D01*
X1825956Y76940D01*
X1827456D01*
X1828956Y77607D01*
X1829956Y78606D01*
X1830456Y79939D01*
X1830206Y81940D01*
X1829206Y82940D01*
X1824706Y84940D01*
X1823706Y87274D01*
X1824206Y88940D01*
X1825206Y89940D01*
X1826706Y90273D01*
X1828206Y89940D01*
X1829706Y88940D01*
G01X1846706Y90273D02*
Y76940D01*
G01Y95606D02*
X1846206Y95940D01*
Y96607D01*
X1846706Y96940D01*
X1847206Y96607D01*
Y95940D01*
X1846706Y95606D01*
G01X1866706Y76940D02*
X1865206Y77273D01*
X1863706Y78606D01*
X1862706Y80940D01*
X1862206Y83606D01*
X1862706Y86273D01*
X1863706Y88607D01*
X1865206Y89940D01*
X1866706Y90273D01*
X1868206Y89940D01*
X1869706Y88607D01*
X1870706Y86273D01*
X1870956Y83606D01*
X1870706Y80940D01*
X1869706Y78606D01*
X1868206Y77273D01*
X1866706Y76940D01*
G01X1882456D02*
Y90273D01*
G01Y86940D02*
X1883456Y88607D01*
X1884956Y89940D01*
X1886956Y90273D01*
X1888706Y89940D01*
X1890206Y88607D01*
X1890956Y86273D01*
Y76940D01*
G01X1747369Y64094D02*
Y109220D01*
G01Y64094D02*
X2123420D01*
G01X1764408Y120954D02*
Y140954D01*
X1770408D01*
X1772408Y139954D01*
X1773908Y137621D01*
X1774408Y134954D01*
X1773908Y132287D01*
X1772658Y130287D01*
X1770408Y129287D01*
X1764408D01*
G01X1794908Y139287D02*
X1793408Y140287D01*
X1791658Y140954D01*
X1789658D01*
X1787408Y139954D01*
X1785658Y138287D01*
X1784408Y136287D01*
X1783408Y132954D01*
X1783158Y129954D01*
X1783658Y126954D01*
X1784408Y124954D01*
X1785908Y122954D01*
X1787658Y121621D01*
X1789408Y120954D01*
X1791158D01*
X1792908Y121621D01*
X1794408Y122620D01*
X1795658Y123953D01*
G01X1811408Y131621D02*
X1812408Y132621D01*
X1813158Y134287D01*
X1813658Y136621D01*
X1813158Y138621D01*
X1812158Y139954D01*
X1810408Y140954D01*
X1803658D01*
Y120954D01*
X1811908D01*
X1813658Y122287D01*
X1814658Y124287D01*
X1815158Y126621D01*
X1814658Y128954D01*
X1813158Y130954D01*
X1811408Y131621D01*
X1803658D01*
G01X1843658Y120954D02*
Y140954D01*
X1855158Y120954D01*
Y140954D01*
G01X1869408Y120954D02*
X1867908Y121287D01*
X1866408Y122620D01*
X1865408Y124954D01*
X1864908Y127620D01*
X1865408Y130287D01*
X1866408Y132621D01*
X1867908Y133954D01*
X1869408Y134287D01*
X1870908Y133954D01*
X1872408Y132621D01*
X1873408Y130287D01*
X1873658Y127620D01*
X1873408Y124954D01*
X1872408Y122620D01*
X1870908Y121287D01*
X1869408Y120954D01*
G01X1889408Y120287D02*
X1888908Y120621D01*
Y121287D01*
X1889408Y121621D01*
X1889908Y121287D01*
Y120621D01*
X1889408Y120287D01*
G01X1747369Y109220D02*
Y214489D01*
G01Y109220D02*
X2537075D01*
G01X1772970Y165167D02*
Y192726D01*
X1781926Y169760D01*
X1790883Y192726D01*
Y165167D01*
G01X1809485D02*
X1807419Y165626D01*
X1805352Y167463D01*
X1803973Y170678D01*
X1803285Y174353D01*
X1803973Y178028D01*
X1805352Y181243D01*
X1807419Y183080D01*
X1809485Y183539D01*
X1811552Y183080D01*
X1813619Y181243D01*
X1814997Y178028D01*
X1815342Y174353D01*
X1814997Y170678D01*
X1813619Y167463D01*
X1811552Y165626D01*
X1809485Y165167D01*
G01X1843245Y192726D02*
Y165167D01*
G01Y169300D02*
X1841867Y167004D01*
X1839800Y165626D01*
X1837389Y165167D01*
X1834633Y166085D01*
X1832566Y168382D01*
X1831188Y171138D01*
X1830844Y174353D01*
X1831188Y177568D01*
X1832566Y180325D01*
X1834633Y182621D01*
X1837389Y183539D01*
X1839800Y183080D01*
X1841523Y182161D01*
X1843245Y180325D01*
G01X1859436Y177568D02*
X1870460D01*
X1869426Y180784D01*
X1867704Y182621D01*
X1865293Y183539D01*
X1862881Y183080D01*
X1860814Y181702D01*
X1859436Y178487D01*
X1858747Y175731D01*
Y172975D01*
X1859436Y170219D01*
X1861158Y167463D01*
X1863226Y165626D01*
X1865637Y165167D01*
X1868049Y166085D01*
X1870460Y168841D01*
G01X1892162Y165167D02*
Y192726D01*
G01X1747369Y154346D02*
X2537075D01*
G01X1747369Y214489D02*
X2537075D01*
G01X1777533Y2097521D02*
Y2108883D01*
X1775829Y2106611D01*
G01Y2097521D02*
X1779237D01*
G01X1788896D02*
Y2108883D01*
X1787192Y2106611D01*
G01Y2097521D02*
X1790600D01*
G01X1828730Y-2912D02*
X1833552Y-30471D01*
X1839064Y-2912D01*
X1844576Y-30471D01*
X1849399Y-2912D01*
G01X1866623Y-12099D02*
Y-30471D01*
G01Y-4750D02*
X1865934Y-4290D01*
Y-3371D01*
X1866623Y-2912D01*
X1867313Y-3371D01*
Y-4290D01*
X1866623Y-4750D01*
G01X1889015Y-27256D02*
X1890737Y-29093D01*
X1893149Y-30471D01*
X1895216D01*
X1897283Y-29553D01*
X1898661Y-28175D01*
X1899350Y-26338D01*
X1899005Y-23581D01*
X1897628Y-22203D01*
X1891426Y-19448D01*
X1890049Y-16232D01*
X1890737Y-13936D01*
X1892116Y-12558D01*
X1894182Y-12099D01*
X1896249Y-12558D01*
X1898316Y-13936D01*
G01X1921741Y-2912D02*
Y-30471D01*
G01X1916919Y-12099D02*
X1926564D01*
G01X1944478Y-30471D02*
Y-12099D01*
G01Y-15773D02*
X1946200Y-13936D01*
X1947923Y-12558D01*
X1950334Y-12099D01*
X1952056Y-12558D01*
X1954123Y-13936D01*
G01X1976859Y-30471D02*
X1974793Y-30012D01*
X1972726Y-28175D01*
X1971347Y-24960D01*
X1970659Y-21285D01*
X1971347Y-17610D01*
X1972726Y-14395D01*
X1974793Y-12558D01*
X1976859Y-12099D01*
X1978926Y-12558D01*
X1980993Y-14395D01*
X1982371Y-17610D01*
X1982716Y-21285D01*
X1982371Y-24960D01*
X1980993Y-28175D01*
X1978926Y-30012D01*
X1976859Y-30471D01*
G01X1998562D02*
Y-12099D01*
G01Y-16692D02*
X1999940Y-14395D01*
X2002007Y-12558D01*
X2004763Y-12099D01*
X2007174Y-12558D01*
X2009241Y-14395D01*
X2010275Y-17610D01*
Y-30471D01*
G01X2067115Y-5209D02*
X2065048Y-3830D01*
X2062637Y-2912D01*
X2059881D01*
X2056780Y-4290D01*
X2054369Y-6587D01*
X2052647Y-9343D01*
X2051268Y-13936D01*
X2050924Y-18070D01*
X2051613Y-22203D01*
X2052647Y-24960D01*
X2054714Y-27716D01*
X2057125Y-29553D01*
X2059536Y-30471D01*
X2061948D01*
X2064359Y-29553D01*
X2066426Y-28175D01*
X2068149Y-26338D01*
G01X2087095Y-30471D02*
X2085029Y-30012D01*
X2082962Y-28175D01*
X2081583Y-24960D01*
X2080895Y-21285D01*
X2081583Y-17610D01*
X2082962Y-14395D01*
X2085029Y-12558D01*
X2087095Y-12099D01*
X2089162Y-12558D01*
X2091229Y-14395D01*
X2092607Y-17610D01*
X2092952Y-21285D01*
X2092607Y-24960D01*
X2091229Y-28175D01*
X2089162Y-30012D01*
X2087095Y-30471D01*
G01X2109832D02*
Y-12099D01*
G01Y-15773D02*
X2111554Y-13936D01*
X2113277Y-12558D01*
X2115688Y-12099D01*
X2117410Y-12558D01*
X2119477Y-13936D01*
G01X2136013Y-39657D02*
Y-12099D01*
G01Y-16232D02*
X2137735Y-13936D01*
X2139457Y-12558D01*
X2142213Y-12099D01*
X2144625Y-12558D01*
X2147036Y-14854D01*
X2148070Y-18070D01*
X2148414Y-21285D01*
X2148070Y-24500D01*
X2147036Y-27716D01*
X2144969Y-29553D01*
X2142213Y-30471D01*
X2139802Y-30012D01*
X2137391Y-28634D01*
X2136013Y-26797D01*
G01X2169772Y-30471D02*
X2167706Y-30012D01*
X2165639Y-28175D01*
X2164260Y-24960D01*
X2163572Y-21285D01*
X2164260Y-17610D01*
X2165639Y-14395D01*
X2167706Y-12558D01*
X2169772Y-12099D01*
X2171839Y-12558D01*
X2173906Y-14395D01*
X2175284Y-17610D01*
X2175629Y-21285D01*
X2175284Y-24960D01*
X2173906Y-28175D01*
X2171839Y-30012D01*
X2169772Y-30471D01*
G01X2192509D02*
Y-12099D01*
G01Y-15773D02*
X2194231Y-13936D01*
X2195954Y-12558D01*
X2198365Y-12099D01*
X2200087Y-12558D01*
X2202154Y-13936D01*
G01X2231091Y-30471D02*
Y-12099D01*
G01Y-15313D02*
X2229713Y-13477D01*
X2227646Y-12558D01*
X2225235Y-12099D01*
X2222824Y-13017D01*
X2220757Y-14854D01*
X2219378Y-17610D01*
X2218690Y-21285D01*
X2219378Y-24960D01*
X2220757Y-27716D01*
X2222824Y-29553D01*
X2225235Y-30471D01*
X2227646Y-30012D01*
X2229713Y-28634D01*
X2231091Y-26797D01*
G01X2252449Y-2912D02*
Y-30471D01*
G01X2247627Y-12099D02*
X2257272D01*
G01X2280008D02*
Y-30471D01*
G01Y-4750D02*
X2279319Y-4290D01*
Y-3371D01*
X2280008Y-2912D01*
X2280698Y-3371D01*
Y-4290D01*
X2280008Y-4750D01*
G01X2307567Y-30471D02*
X2305501Y-30012D01*
X2303434Y-28175D01*
X2302055Y-24960D01*
X2301367Y-21285D01*
X2302055Y-17610D01*
X2303434Y-14395D01*
X2305501Y-12558D01*
X2307567Y-12099D01*
X2309634Y-12558D01*
X2311701Y-14395D01*
X2313079Y-17610D01*
X2313424Y-21285D01*
X2313079Y-24960D01*
X2311701Y-28175D01*
X2309634Y-30012D01*
X2307567Y-30471D01*
G01X2329270D02*
Y-12099D01*
G01Y-16692D02*
X2330648Y-14395D01*
X2332715Y-12558D01*
X2335471Y-12099D01*
X2337882Y-12558D01*
X2339949Y-14395D01*
X2340983Y-17610D01*
Y-30471D01*
G01X1887841Y-65085D02*
Y-84022D01*
G01X1903043Y-65085D02*
X2553477D01*
G01X1888787Y2112671D02*
Y2093734D01*
G01X1966362Y30007D02*
Y50007D01*
G01X1975862D02*
X1966362Y37673D01*
G01X1977362Y30007D02*
X1970612Y43340D01*
G01X1988112Y39007D02*
X1996112D01*
X1995362Y41340D01*
X1994112Y42673D01*
X1992362Y43340D01*
X1990612Y43007D01*
X1989112Y42007D01*
X1988112Y39673D01*
X1987612Y37673D01*
Y35674D01*
X1988112Y33673D01*
X1989362Y31673D01*
X1990862Y30340D01*
X1992612Y30007D01*
X1994362Y30674D01*
X1996112Y32673D01*
G01X2007612Y30007D02*
Y43340D01*
G01Y40007D02*
X2008612Y41674D01*
X2010112Y43007D01*
X2012112Y43340D01*
X2013862Y43007D01*
X2015362Y41674D01*
X2016112Y39340D01*
Y30007D01*
G01X1935394Y18968D02*
Y214489D01*
G01X1977609Y122928D02*
Y142928D01*
X1974609Y138928D01*
G01Y122928D02*
X1980609D01*
G01X1992859Y139595D02*
X1994359Y141594D01*
X1996109Y142595D01*
X1998109Y142928D01*
X2000609Y142261D01*
X2002359Y140595D01*
X2002859Y138595D01*
X2002609Y136594D01*
X2001609Y134928D01*
X1996609Y131595D01*
X1994359Y129261D01*
X1992859Y125927D01*
X1992359Y122928D01*
X2002859D01*
G01X2020609D02*
Y142928D01*
X2011359Y128595D01*
X2023859D01*
G01X2032109Y126928D02*
X2033609Y124594D01*
X2035609Y123261D01*
X2037859Y122928D01*
X2039859Y123261D01*
X2041859Y124928D01*
X2043109Y126928D01*
X2043359Y128928D01*
X2042859Y131261D01*
X2041109Y132928D01*
X2039359Y133595D01*
X2037109D01*
G01X2039359D02*
X2040859Y134595D01*
X2042109Y136261D01*
X2042609Y138261D01*
X2042109Y140261D01*
X2040859Y141928D01*
X2038609Y142928D01*
X2036359Y142595D01*
X2034109Y141261D01*
G01X2052109Y126928D02*
X2053609Y124594D01*
X2055609Y123261D01*
X2057859Y122928D01*
X2059859Y123261D01*
X2061859Y124928D01*
X2063109Y126928D01*
X2063359Y128928D01*
X2062859Y131261D01*
X2061109Y132928D01*
X2059359Y133595D01*
X2057109D01*
G01X2059359D02*
X2060859Y134595D01*
X2062109Y136261D01*
X2062609Y138261D01*
X2062109Y140261D01*
X2060859Y141928D01*
X2058609Y142928D01*
X2056359Y142595D01*
X2054109Y141261D01*
G01X1960320Y168873D02*
Y192495D01*
G01X1971541D02*
X1960320Y177928D01*
G01X1973313Y168873D02*
X1965340Y184621D01*
G01X1983648Y168873D02*
Y192495D01*
X1997231Y168873D01*
Y192495D01*
G01X2014062Y168873D02*
X2011700Y169267D01*
X2009633Y170841D01*
X2007862Y173203D01*
X2006680Y175960D01*
X2006090Y179109D01*
Y182259D01*
X2006680Y185408D01*
X2007862Y188165D01*
X2009633Y190526D01*
X2011700Y192101D01*
X2014062Y192495D01*
X2016425Y192101D01*
X2018492Y190526D01*
X2020263Y188165D01*
X2021445Y185408D01*
X2022035Y182259D01*
Y179109D01*
X2021445Y175960D01*
X2020263Y173203D01*
X2018492Y170841D01*
X2016425Y169267D01*
X2014062Y168873D01*
G01X2031485D02*
X2043886Y192495D01*
G01X2031485D02*
X2043886Y168873D01*
G01X2079321D02*
Y192495D01*
X2090542D01*
G01X2086408Y181078D02*
X2079321D01*
G01X2101172Y168873D02*
X2108554Y192495D01*
X2115937Y168873D01*
G01X2113279Y177140D02*
X2103830D01*
G01X2125386Y168873D02*
Y192495D01*
X2138969Y168873D01*
Y192495D01*
G01X2185920Y190526D02*
X2184148Y191708D01*
X2182081Y192495D01*
X2179719D01*
X2177061Y191313D01*
X2174994Y189345D01*
X2173518Y186983D01*
X2172336Y183046D01*
X2172041Y179503D01*
X2172632Y175960D01*
X2173518Y173597D01*
X2175290Y171235D01*
X2177357Y169660D01*
X2179423Y168873D01*
X2181490D01*
X2183557Y169660D01*
X2185329Y170841D01*
X2186806Y172416D01*
G01X2203046Y168873D02*
X2200684Y169267D01*
X2198617Y170841D01*
X2196846Y173203D01*
X2195664Y175960D01*
X2195074Y179109D01*
Y182259D01*
X2195664Y185408D01*
X2196846Y188165D01*
X2198617Y190526D01*
X2200684Y192101D01*
X2203046Y192495D01*
X2205409Y192101D01*
X2207476Y190526D01*
X2209247Y188165D01*
X2210429Y185408D01*
X2211019Y182259D01*
Y179109D01*
X2210429Y175960D01*
X2209247Y173203D01*
X2207476Y170841D01*
X2205409Y169267D01*
X2203046Y168873D01*
G01X2219878D02*
Y192495D01*
X2233461Y168873D01*
Y192495D01*
G01X2250292D02*
Y168873D01*
G01X2243501Y192495D02*
X2257084D01*
G01X2268010Y168873D02*
Y192495D01*
X2275392D01*
X2277754Y191313D01*
X2279231Y189739D01*
X2279821Y186589D01*
X2279231Y183440D01*
X2277459Y181472D01*
X2275392Y180290D01*
X2268010D01*
G01X2275392D02*
X2279821Y168873D01*
G01X2297538D02*
X2295176Y169267D01*
X2293109Y170841D01*
X2291338Y173203D01*
X2290156Y175960D01*
X2289566Y179109D01*
Y182259D01*
X2290156Y185408D01*
X2291338Y188165D01*
X2293109Y190526D01*
X2295176Y192101D01*
X2297538Y192495D01*
X2299901Y192101D01*
X2301968Y190526D01*
X2303739Y188165D01*
X2304921Y185408D01*
X2305511Y182259D01*
Y179109D01*
X2304921Y175960D01*
X2303739Y173203D01*
X2301968Y170841D01*
X2299901Y169267D01*
X2297538Y168873D01*
G01X2315256Y192495D02*
Y168873D01*
X2327067D01*
G01X2370770Y181472D02*
X2371951Y182652D01*
X2372837Y184621D01*
X2373428Y187377D01*
X2372837Y189739D01*
X2371656Y191313D01*
X2369589Y192495D01*
X2361616D01*
Y168873D01*
X2371361D01*
X2373428Y170447D01*
X2374608Y172810D01*
X2375199Y175566D01*
X2374608Y178321D01*
X2372837Y180684D01*
X2370770Y181472D01*
X2361616D01*
G01X2392030Y168873D02*
X2389668Y169267D01*
X2387601Y170841D01*
X2385830Y173203D01*
X2384648Y175960D01*
X2384058Y179109D01*
Y182259D01*
X2384648Y185408D01*
X2385830Y188165D01*
X2387601Y190526D01*
X2389668Y192101D01*
X2392030Y192495D01*
X2394393Y192101D01*
X2396460Y190526D01*
X2398231Y188165D01*
X2399413Y185408D01*
X2400003Y182259D01*
Y179109D01*
X2399413Y175960D01*
X2398231Y173203D01*
X2396460Y170841D01*
X2394393Y169267D01*
X2392030Y168873D01*
G01X2408271D02*
X2415653Y192495D01*
X2423036Y168873D01*
G01X2420378Y177140D02*
X2410929D01*
G01X2433371Y168873D02*
Y192495D01*
X2440753D01*
X2443115Y191313D01*
X2444592Y189739D01*
X2445182Y186589D01*
X2444592Y183440D01*
X2442820Y181472D01*
X2440753Y180290D01*
X2433371D01*
G01X2440753D02*
X2445182Y168873D01*
G01X2456403D02*
Y192495D01*
X2462309D01*
X2464671Y191313D01*
X2466443Y189739D01*
X2467920Y187377D01*
X2469100Y184621D01*
X2469396Y180684D01*
X2469100Y176747D01*
X2467920Y173991D01*
X2466443Y171628D01*
X2464671Y170054D01*
X2462309Y168873D01*
X2456403D01*
G01X2480617Y176747D02*
X2486522Y192495D01*
X2492428Y176747D01*
G01X2486522Y192495D02*
Y160999D01*
G01X2506602Y192495D02*
X2513688D01*
G01X2510145D02*
Y168873D01*
G01X2506602D02*
X2513688D01*
G01X1995308Y-80235D02*
Y-68873D01*
X1993604Y-71145D01*
G01Y-80235D02*
X1997012D01*
G01X2003972Y-70767D02*
X2004825Y-69631D01*
X2005819Y-69062D01*
X2006955Y-68873D01*
X2008375Y-69252D01*
X2009370Y-70199D01*
X2009654Y-71335D01*
X2009512Y-72471D01*
X2008943Y-73418D01*
X2006103Y-75311D01*
X2004825Y-76637D01*
X2003972Y-78531D01*
X2003688Y-80235D01*
X2009654D01*
G01X1986889Y88713D02*
X1988389Y90712D01*
X1990139Y91713D01*
X1992139Y92046D01*
X1994639Y91379D01*
X1996389Y89713D01*
X1996889Y87713D01*
X1996639Y85712D01*
X1995639Y84046D01*
X1990639Y80713D01*
X1988389Y78379D01*
X1986889Y75045D01*
X1986389Y72046D01*
X1996889D01*
G01X2005389D02*
X2011639Y92046D01*
X2017889Y72046D01*
G01X2015639Y79046D02*
X2007639D01*
G01X1995308Y2097521D02*
Y2108883D01*
X1993604Y2106611D01*
G01Y2097521D02*
X1997012D01*
G01X2003972Y2106989D02*
X2004825Y2108125D01*
X2005819Y2108694D01*
X2006955Y2108883D01*
X2008375Y2108504D01*
X2009370Y2107557D01*
X2009654Y2106421D01*
X2009512Y2105285D01*
X2008943Y2104338D01*
X2006103Y2102445D01*
X2004825Y2101119D01*
X2003972Y2099225D01*
X2003688Y2097521D01*
X2009654D01*
G01X2108457Y-65085D02*
Y-84022D01*
G01X2123420Y64094D02*
X2537075D01*
G01X2108457Y2112671D02*
Y2093734D01*
G01X2177539Y28032D02*
Y48032D01*
X2182539D01*
X2184539Y47032D01*
X2186039Y45699D01*
X2187289Y43699D01*
X2188289Y41365D01*
X2188539Y38032D01*
X2188289Y34698D01*
X2187289Y32365D01*
X2186039Y30365D01*
X2184539Y29032D01*
X2182539Y28032D01*
X2177539D01*
G01X2207539D02*
Y41365D01*
G01Y39032D02*
X2206539Y40365D01*
X2205039Y41032D01*
X2203289Y41365D01*
X2201539Y40698D01*
X2200039Y39365D01*
X2199039Y37365D01*
X2198539Y34698D01*
X2199039Y32032D01*
X2200039Y30032D01*
X2201539Y28699D01*
X2203289Y28032D01*
X2205039Y28365D01*
X2206539Y29365D01*
X2207539Y30698D01*
G01X2223039Y48032D02*
Y28032D01*
G01X2219539Y41365D02*
X2226539D01*
G01X2239289Y37032D02*
X2247289D01*
X2246539Y39365D01*
X2245289Y40698D01*
X2243539Y41365D01*
X2241789Y41032D01*
X2240289Y40032D01*
X2239289Y37698D01*
X2238789Y35698D01*
Y33699D01*
X2239289Y31698D01*
X2240539Y29698D01*
X2242039Y28365D01*
X2243789Y28032D01*
X2245539Y28699D01*
X2247289Y30698D01*
G01X2140465Y96740D02*
Y76740D01*
G01X2134715Y96740D02*
X2146215D01*
G01X2156215Y76740D02*
Y96740D01*
G01Y87074D02*
X2157465Y88740D01*
X2158715Y89740D01*
X2160715Y90073D01*
X2162215Y89740D01*
X2163965Y88407D01*
X2164715Y86406D01*
Y76740D01*
G01X2180465Y90073D02*
Y76740D01*
G01Y95406D02*
X2179965Y95740D01*
Y96407D01*
X2180465Y96740D01*
X2180965Y96407D01*
Y95740D01*
X2180465Y95406D01*
G01X2204465Y88407D02*
X2202715Y89740D01*
X2201215Y90073D01*
X2199215Y89406D01*
X2197715Y88073D01*
X2196715Y85740D01*
X2196465Y83406D01*
X2196715Y81073D01*
X2197715Y79073D01*
X2199215Y77407D01*
X2201215Y76740D01*
X2202965Y77407D01*
X2204465Y78740D01*
G01X2216215Y76740D02*
Y96740D01*
G01X2224215Y90073D02*
X2216215Y82407D01*
G01X2219465Y85407D02*
X2224715Y76740D01*
G01X2236215D02*
Y90073D01*
G01Y86740D02*
X2237215Y88407D01*
X2238715Y89740D01*
X2240715Y90073D01*
X2242465Y89740D01*
X2243965Y88407D01*
X2244715Y86073D01*
Y76740D01*
G01X2256715Y85740D02*
X2264715D01*
X2263965Y88073D01*
X2262715Y89406D01*
X2260965Y90073D01*
X2259215Y89740D01*
X2257715Y88740D01*
X2256715Y86406D01*
X2256215Y84406D01*
Y82407D01*
X2256715Y80406D01*
X2257965Y78406D01*
X2259465Y77073D01*
X2261215Y76740D01*
X2262965Y77407D01*
X2264715Y79406D01*
G01X2276715Y79073D02*
X2277965Y77740D01*
X2279715Y76740D01*
X2281215D01*
X2282715Y77407D01*
X2283715Y78406D01*
X2284215Y79739D01*
X2283965Y81740D01*
X2282965Y82740D01*
X2278465Y84740D01*
X2277465Y87074D01*
X2277965Y88740D01*
X2278965Y89740D01*
X2280465Y90073D01*
X2281965Y89740D01*
X2283465Y88740D01*
G01X2296715Y79073D02*
X2297965Y77740D01*
X2299715Y76740D01*
X2301215D01*
X2302715Y77407D01*
X2303715Y78406D01*
X2304215Y79739D01*
X2303965Y81740D01*
X2302965Y82740D01*
X2298465Y84740D01*
X2297465Y87074D01*
X2297965Y88740D01*
X2298965Y89740D01*
X2300465Y90073D01*
X2301965Y89740D01*
X2303465Y88740D01*
G01X2214978Y-80235D02*
Y-68873D01*
X2213274Y-71145D01*
G01Y-80235D02*
X2216682D01*
G01X2223216Y-77963D02*
X2224068Y-79288D01*
X2225205Y-80046D01*
X2226483Y-80235D01*
X2227619Y-80046D01*
X2228756Y-79099D01*
X2229466Y-77963D01*
X2229608Y-76826D01*
X2229324Y-75501D01*
X2228329Y-74554D01*
X2227335Y-74175D01*
X2226057D01*
G01X2227335D02*
X2228187Y-73607D01*
X2228898Y-72661D01*
X2229182Y-71524D01*
X2228898Y-70388D01*
X2228187Y-69441D01*
X2226909Y-68873D01*
X2225631Y-69062D01*
X2224353Y-69820D01*
G01X2214978Y2097521D02*
Y2108883D01*
X2213274Y2106611D01*
G01Y2097521D02*
X2216682D01*
G01X2223216Y2099793D02*
X2224068Y2098468D01*
X2225205Y2097710D01*
X2226483Y2097521D01*
X2227619Y2097710D01*
X2228756Y2098657D01*
X2229466Y2099793D01*
X2229608Y2100930D01*
X2229324Y2102255D01*
X2228329Y2103202D01*
X2227335Y2103581D01*
X2226057D01*
G01X2227335D02*
X2228187Y2104149D01*
X2228898Y2105095D01*
X2229182Y2106232D01*
X2228898Y2107368D01*
X2228187Y2108315D01*
X2226909Y2108883D01*
X2225631Y2108694D01*
X2224353Y2107936D01*
G01X2222768Y2093734D02*
X2553476D01*
G01X2328126Y-65085D02*
Y-84022D01*
G01Y2112671D02*
Y2093734D01*
G01X2341770Y46674D02*
X2343270Y48673D01*
X2345020Y49674D01*
X2347020Y50007D01*
X2349520Y49340D01*
X2351270Y47674D01*
X2351770Y45674D01*
X2351520Y43673D01*
X2350520Y42007D01*
X2345520Y38674D01*
X2343270Y36340D01*
X2341770Y33006D01*
X2341270Y30007D01*
X2351770D01*
G01X2366520Y50007D02*
X2364520Y49340D01*
X2363020Y47674D01*
X2362020Y45674D01*
X2361270Y43007D01*
X2361020Y40007D01*
X2361270Y37007D01*
X2362020Y34340D01*
X2363020Y32340D01*
X2364520Y30674D01*
X2366520Y30007D01*
X2368520Y30674D01*
X2370020Y32340D01*
X2371020Y34340D01*
X2371770Y37007D01*
X2372020Y40007D01*
X2371770Y43007D01*
X2371020Y45674D01*
X2370020Y47674D01*
X2368520Y49340D01*
X2366520Y50007D01*
G01X2386520Y30007D02*
Y50007D01*
X2383520Y46007D01*
G01Y30007D02*
X2389520D01*
G01X2401770Y46674D02*
X2403270Y48673D01*
X2405020Y49674D01*
X2407020Y50007D01*
X2409520Y49340D01*
X2411270Y47674D01*
X2411770Y45674D01*
X2411520Y43673D01*
X2410520Y42007D01*
X2405520Y38674D01*
X2403270Y36340D01*
X2401770Y33006D01*
X2401270Y30007D01*
X2411770D01*
G01X2423270Y36673D02*
X2429770D01*
G01X2446520Y30007D02*
Y50007D01*
X2443520Y46007D01*
G01Y30007D02*
X2449520D01*
G01X2466520Y50007D02*
X2464520Y49340D01*
X2463020Y47674D01*
X2462020Y45674D01*
X2461270Y43007D01*
X2461020Y40007D01*
X2461270Y37007D01*
X2462020Y34340D01*
X2463020Y32340D01*
X2464520Y30674D01*
X2466520Y30007D01*
X2468520Y30674D01*
X2470020Y32340D01*
X2471020Y34340D01*
X2471770Y37007D01*
X2472020Y40007D01*
X2471770Y43007D01*
X2471020Y45674D01*
X2470020Y47674D01*
X2468520Y49340D01*
X2466520Y50007D01*
G01X2483270Y36673D02*
X2489770D01*
G01X2506520Y30007D02*
Y50007D01*
X2503520Y46007D01*
G01Y30007D02*
X2509520D01*
G01X2521020Y33006D02*
X2522520Y31340D01*
X2524270Y30340D01*
X2526520Y30007D01*
X2528770Y30674D01*
X2530520Y32007D01*
X2531770Y34340D01*
X2532020Y37007D01*
X2531520Y39673D01*
X2530270Y41340D01*
X2528520Y42673D01*
X2526770Y43007D01*
X2525020Y42673D01*
X2522770Y41340D01*
X2523520Y50007D01*
X2530270D01*
G01X2354414Y78715D02*
Y98715D01*
X2351414Y94715D01*
G01Y78715D02*
X2357414D01*
G01X2374414Y78048D02*
X2373914Y78382D01*
Y79048D01*
X2374414Y79382D01*
X2374914Y79048D01*
Y78382D01*
X2374414Y78048D01*
G01X2389664Y87048D02*
X2391414Y89382D01*
X2392914Y90715D01*
X2394914Y91381D01*
X2396664Y90715D01*
X2397914Y89382D01*
X2398914Y87382D01*
X2399164Y85048D01*
X2398914Y83048D01*
X2397914Y81048D01*
X2396414Y79382D01*
X2394664Y78715D01*
X2392664Y79382D01*
X2390914Y81381D01*
X2389914Y84382D01*
X2389664Y87715D01*
X2390164Y92048D01*
X2390914Y94382D01*
X2392164Y96715D01*
X2393914Y98382D01*
X2395664Y98715D01*
X2397414Y98048D01*
X2398664Y96382D01*
G01X2426914Y78715D02*
Y92048D01*
G01Y88381D02*
X2427664Y90048D01*
X2428914Y91381D01*
X2430664Y92048D01*
X2432414Y91381D01*
X2433664Y90048D01*
X2434414Y88381D01*
Y78715D01*
G01Y88381D02*
X2435164Y90048D01*
X2436414Y91381D01*
X2438164Y92048D01*
X2439914Y91381D01*
X2441164Y90048D01*
X2441914Y88048D01*
Y78715D01*
G01X2446914D02*
Y92048D01*
G01Y88381D02*
X2447664Y90048D01*
X2448914Y91381D01*
X2450664Y92048D01*
X2452414Y91381D01*
X2453664Y90048D01*
X2454414Y88381D01*
Y78715D01*
G01Y88381D02*
X2455164Y90048D01*
X2456414Y91381D01*
X2458164Y92048D01*
X2459914Y91381D01*
X2461164Y90048D01*
X2461914Y88048D01*
Y78715D01*
G01X2434647Y-80235D02*
Y-68873D01*
X2432943Y-71145D01*
G01Y-80235D02*
X2436351D01*
G01X2447714D02*
Y-68873D01*
X2442459Y-77016D01*
X2449561D01*
G01X2434647Y2097521D02*
Y2108883D01*
X2432943Y2106611D01*
G01Y2097521D02*
X2436351D01*
G01X2447714D02*
Y2108883D01*
X2442459Y2100740D01*
X2449561D01*
G01X2537075Y-41200D02*
Y156118D01*
G01X2499470Y-41200D02*
X2537075D01*
G01Y156118D02*
Y214489D01*
G01X2572413Y2112671D02*
Y-84022D01*
G01X2553476Y2093734D02*
Y-65085D01*
G01X2553477Y79600D02*
Y-65085D01*
G01X2560388Y39447D02*
X2561099Y38311D01*
X2561951Y37554D01*
X2562945Y37175D01*
X2564081Y37554D01*
X2564933Y38311D01*
X2565786Y39447D01*
X2566070Y40962D01*
Y48537D01*
G01X2553476Y150797D02*
X2572413D01*
G01X2561525Y264419D02*
X2564933D01*
G01X2563229D02*
Y253057D01*
G01X2561525D02*
X2564933D01*
G01X2553476Y366679D02*
X2572413D01*
G01X2560246Y468749D02*
Y480111D01*
G01X2566212D02*
Y468749D01*
G01Y474430D02*
X2560246D01*
G01X2553476Y582561D02*
X2572413D01*
G01X2564081Y690312D02*
X2566922D01*
Y686903D01*
X2566070Y685767D01*
X2565075Y685010D01*
X2563655Y684631D01*
X2562235Y685010D01*
X2561241Y685767D01*
X2560388Y686903D01*
X2559820Y688229D01*
X2559536Y689744D01*
Y691069D01*
X2559820Y692205D01*
X2560388Y693531D01*
X2561241Y694667D01*
X2562093Y695425D01*
X2563229Y695993D01*
X2564223D01*
X2565359Y695614D01*
X2566212Y694857D01*
G01X2553476Y798443D02*
X2572413D01*
G01X2560151Y900703D02*
Y912065D01*
X2565549D01*
G01X2563560Y906573D02*
X2560151D01*
G01X2553476Y1014325D02*
X2572413D01*
G01X2566070Y1116774D02*
X2560388D01*
Y1128136D01*
X2566070D01*
G01X2563797Y1122644D02*
X2560388D01*
G01X2553476Y1230206D02*
X2572413D01*
G01X2560104Y1332466D02*
Y1343828D01*
X2562945D01*
X2564081Y1343260D01*
X2564933Y1342502D01*
X2565644Y1341366D01*
X2566212Y1340040D01*
X2566354Y1338147D01*
X2566212Y1336253D01*
X2565644Y1334928D01*
X2564933Y1333791D01*
X2564081Y1333034D01*
X2562945Y1332466D01*
X2560104D01*
G01X2553476Y1446088D02*
X2572413D01*
G01X2566354Y1558953D02*
X2565501Y1559521D01*
X2564507Y1559900D01*
X2563371D01*
X2562093Y1559332D01*
X2561099Y1558385D01*
X2560388Y1557249D01*
X2559820Y1555355D01*
X2559678Y1553651D01*
X2559962Y1551947D01*
X2560388Y1550810D01*
X2561241Y1549674D01*
X2562235Y1548917D01*
X2563229Y1548538D01*
X2564223D01*
X2565217Y1548917D01*
X2566070Y1549485D01*
X2566780Y1550242D01*
G01X2553476Y1661970D02*
X2572413D01*
G01X2564365Y1770290D02*
X2564933Y1770858D01*
X2565359Y1771804D01*
X2565644Y1773130D01*
X2565359Y1774266D01*
X2564791Y1775024D01*
X2563797Y1775592D01*
X2559962D01*
Y1764230D01*
X2564649D01*
X2565644Y1764987D01*
X2566212Y1766124D01*
X2566496Y1767449D01*
X2566212Y1768775D01*
X2565359Y1769911D01*
X2564365Y1770290D01*
X2559962D01*
G01X2553287Y1877852D02*
X2572224D01*
G01X2559678Y1980112D02*
X2563229Y1991474D01*
X2566780Y1980112D01*
G01X2565501Y1984089D02*
X2560956D01*
G01X2553476Y2093734D02*
Y1999246D01*
M02*
